G04 ================== begin FILE IDENTIFICATION RECORD ==================*
G04 Layout Name:  t6m_pdb_d_0928_1400_274.brd*
G04 Film Name:    ssb.art*
G04 File Format:  Gerber RS274X*
G04 File Origin:  Cadence Allegro 16.3-S048*
G04 Origin Date:  Tue Nov 26 11:01:50 2013*
G04 *
G04 Layer:  BOARD GEOMETRY/OUTLINE*
G04 Layer:  DRAWING FORMAT/TITLE_BLOCK*
G04 Layer:  MANUFACTURING/TP_TEXT_BOTTOM*
G04 Layer:  REF DES/SILKSCREEN_BOTTOM*
G04 Layer:  PACKAGE GEOMETRY/SILKSCREEN_BOTTOM*
G04 Layer:  MANUFACTURING/PHOTOPLOT_OUTLINE*
G04 Layer:  DRAWING FORMAT/TITLE_DATA_SSB*
G04 Layer:  BOARD GEOMETRY/SILKSCREEN_BOTTOM*
G04 *
G04 Offset:    (0.00 0.00)*
G04 Mirror:    No*
G04 Mode:      Positive*
G04 Rotation:  0*
G04 FullContactRelief:  No*
G04 UndefLineWidth:     6.00*
G04 ================== end FILE IDENTIFICATION RECORD ====================*
%FSLAX25Y25*MOIN*%
%IR0*IPPOS*OFA0.00000B0.00000*MIA0B0*SFA1.00000B1.00000*%
%ADD10C,.006*%
G75*
%LPD*%
G75*
G36*
G01X25889Y1056063D02*
X28889Y1063563D01*
X22889D01*
X25889Y1056063D01*
G37*
G36*
G01X25893Y1414328D02*
X28893Y1421828D01*
X22893D01*
X25893Y1414328D01*
G37*
G36*
G01X110935Y328571D02*
X100305Y331327D01*
Y325815D01*
X110935Y328571D01*
G37*
G36*
G01Y676602D02*
X100305Y679358D01*
Y673846D01*
X110935Y676602D01*
G37*
G36*
G01Y1024634D02*
X100305Y1027390D01*
Y1021878D01*
X110935Y1024634D01*
G37*
G36*
G01Y1372665D02*
X100305Y1375421D01*
Y1369909D01*
X110935Y1372665D01*
G37*
G36*
G01Y1720697D02*
X100305Y1723453D01*
Y1717941D01*
X110935Y1720697D01*
G37*
G36*
G01Y2068728D02*
X100305Y2071484D01*
Y2065972D01*
X110935Y2068728D01*
G37*
G36*
G01X170396Y48677D02*
X176396D01*
X173396Y42677D01*
X170396Y48677D01*
G37*
G36*
G01Y223677D02*
X176396D01*
X173396Y217677D01*
X170396Y223677D01*
G37*
G36*
G01Y398677D02*
X176396D01*
X173396Y392677D01*
X170396Y398677D01*
G37*
G36*
G01X170397Y573677D02*
X176397D01*
X173397Y567677D01*
X170397Y573677D01*
G37*
G36*
G01Y748677D02*
X176397D01*
X173397Y742677D01*
X170397Y748677D01*
G37*
G36*
G01X170396Y923677D02*
X176396D01*
X173396Y917677D01*
X170396Y923677D01*
G37*
G36*
G01Y1098677D02*
X176396D01*
X173396Y1092677D01*
X170396Y1098677D01*
G37*
G36*
G01Y1273677D02*
X176396D01*
X173396Y1267677D01*
X170396Y1273677D01*
G37*
G36*
G01Y1448677D02*
X176396D01*
X173396Y1442677D01*
X170396Y1448677D01*
G37*
G36*
G01Y1623677D02*
X176396D01*
X173396Y1617677D01*
X170396Y1623677D01*
G37*
G36*
G01Y1798677D02*
X176396D01*
X173396Y1792677D01*
X170396Y1798677D01*
G37*
G36*
G01Y1973677D02*
X176396D01*
X173396Y1967677D01*
X170396Y1973677D01*
G37*
G54D10*
G01X-723776Y2987387D02*
Y-376795D01*
Y-489221D01*
X1782976D01*
Y-376795D01*
Y2987387D01*
X-723776D01*
G01X-4000Y-62500D02*
Y-137500D01*
X496000D01*
Y-62500D01*
X-4000D01*
G01X104331Y0D02*
X397638D01*
G03X405512Y7874I0J7874D01*
G01Y2078740D01*
G03X397638Y2086614I-7874J0D01*
G01X104331D01*
G03X98425Y2080709I0J-5906D01*
G01Y2076772D01*
G02X92520Y2070866I-5905J-1D01*
G01X5906D01*
G03X0Y2064961I-1J-5905D01*
G01Y21654D01*
G03X5906Y15748I5906J0D01*
G01X92520D01*
G02X98425Y9843I0J-5905D01*
G01Y5906D01*
G03X104331Y0I5906J0D01*
G01X8000Y-127500D02*
Y-132500D01*
G01X6543Y-127500D02*
X9457D01*
G01X14367Y-132500D02*
X11833D01*
Y-127500D01*
X14367D01*
G01X13353Y-129917D02*
X11833D01*
G01X16933Y-127500D02*
Y-132500D01*
X19467D01*
G01X23300Y-132667D02*
X23173Y-132583D01*
Y-132417D01*
X23300Y-132333D01*
X23427Y-132417D01*
Y-132583D01*
X23300Y-132667D01*
G01Y-130417D02*
X23173Y-130333D01*
Y-130167D01*
X23300Y-130083D01*
X23427Y-130167D01*
Y-130333D01*
X23300Y-130417D01*
G01X28083Y-134167D02*
X27450Y-133333D01*
X27133Y-132500D01*
Y-129167D01*
X27450Y-128333D01*
X28083Y-127500D01*
G01X33500D02*
X32993Y-127667D01*
X32613Y-128083D01*
X32360Y-128583D01*
X32170Y-129250D01*
X32107Y-130000D01*
X32170Y-130750D01*
X32360Y-131417D01*
X32613Y-131917D01*
X32993Y-132333D01*
X33500Y-132500D01*
X34007Y-132333D01*
X34387Y-131917D01*
X34640Y-131417D01*
X34830Y-130750D01*
X34893Y-130000D01*
X34830Y-129250D01*
X34640Y-128583D01*
X34387Y-128083D01*
X34007Y-127667D01*
X33500Y-127500D01*
G01X37207Y-131500D02*
X37587Y-132083D01*
X38093Y-132417D01*
X38663Y-132500D01*
X39170Y-132417D01*
X39677Y-132000D01*
X39993Y-131500D01*
X40057Y-131000D01*
X39930Y-130417D01*
X39487Y-130000D01*
X39043Y-129833D01*
X38473D01*
G01X39043D02*
X39423Y-129583D01*
X39740Y-129167D01*
X39867Y-128667D01*
X39740Y-128167D01*
X39423Y-127750D01*
X38853Y-127500D01*
X38283Y-127583D01*
X37713Y-127917D01*
G01X44017Y-134167D02*
X44650Y-133333D01*
X44967Y-132500D01*
Y-129167D01*
X44650Y-128333D01*
X44017Y-127500D01*
G01X47407Y-131500D02*
X47787Y-132083D01*
X48293Y-132417D01*
X48863Y-132500D01*
X49370Y-132417D01*
X49877Y-132000D01*
X50193Y-131500D01*
X50257Y-131000D01*
X50130Y-130417D01*
X49687Y-130000D01*
X49243Y-129833D01*
X48673D01*
G01X49243D02*
X49623Y-129583D01*
X49940Y-129167D01*
X50067Y-128667D01*
X49940Y-128167D01*
X49623Y-127750D01*
X49053Y-127500D01*
X48483Y-127583D01*
X47913Y-127917D01*
G01X52697Y-128333D02*
X53077Y-127833D01*
X53520Y-127583D01*
X54027Y-127500D01*
X54660Y-127667D01*
X55103Y-128083D01*
X55230Y-128583D01*
X55167Y-129083D01*
X54913Y-129500D01*
X53647Y-130333D01*
X53077Y-130917D01*
X52697Y-131750D01*
X52570Y-132500D01*
X55230D01*
G01X58873D02*
X59000Y-131417D01*
X59190Y-130500D01*
X59443Y-129667D01*
X59760Y-128750D01*
X60267Y-127500D01*
X57733D01*
G01X63277Y-130833D02*
X64923D01*
G01X67997Y-128333D02*
X68377Y-127833D01*
X68820Y-127583D01*
X69327Y-127500D01*
X69960Y-127667D01*
X70403Y-128083D01*
X70530Y-128583D01*
X70467Y-129083D01*
X70213Y-129500D01*
X68947Y-130333D01*
X68377Y-130917D01*
X67997Y-131750D01*
X67870Y-132500D01*
X70530D01*
G01X72907Y-131500D02*
X73287Y-132083D01*
X73793Y-132417D01*
X74363Y-132500D01*
X74870Y-132417D01*
X75377Y-132000D01*
X75693Y-131500D01*
X75757Y-131000D01*
X75630Y-130417D01*
X75187Y-130000D01*
X74743Y-129833D01*
X74173D01*
G01X74743D02*
X75123Y-129583D01*
X75440Y-129167D01*
X75567Y-128667D01*
X75440Y-128167D01*
X75123Y-127750D01*
X74553Y-127500D01*
X73983Y-127583D01*
X73413Y-127917D01*
G01X80160Y-132500D02*
Y-127500D01*
X77817Y-131083D01*
X80983D01*
G01X83107Y-131750D02*
X83487Y-132167D01*
X83930Y-132417D01*
X84500Y-132500D01*
X85070Y-132333D01*
X85513Y-132000D01*
X85830Y-131417D01*
X85893Y-130750D01*
X85767Y-130083D01*
X85450Y-129667D01*
X85007Y-129333D01*
X84563Y-129250D01*
X84120Y-129333D01*
X83550Y-129667D01*
X83740Y-127500D01*
X85450D01*
G01X93497Y-132500D02*
Y-127500D01*
X95903D01*
G01X95017Y-129917D02*
X93497D01*
G01X98217Y-132500D02*
X99800Y-127500D01*
X101383Y-132500D01*
G01X100813Y-130750D02*
X98787D01*
G01X103570Y-132500D02*
X106230Y-127500D01*
G01X103570D02*
X106230Y-132500D01*
G01X110000Y-132667D02*
X109873Y-132583D01*
Y-132417D01*
X110000Y-132333D01*
X110127Y-132417D01*
Y-132583D01*
X110000Y-132667D01*
G01Y-130417D02*
X109873Y-130333D01*
Y-130167D01*
X110000Y-130083D01*
X110127Y-130167D01*
Y-130333D01*
X110000Y-130417D01*
G01X114783Y-134167D02*
X114150Y-133333D01*
X113833Y-132500D01*
Y-129167D01*
X114150Y-128333D01*
X114783Y-127500D01*
G01X120200D02*
X119693Y-127667D01*
X119313Y-128083D01*
X119060Y-128583D01*
X118870Y-129250D01*
X118807Y-130000D01*
X118870Y-130750D01*
X119060Y-131417D01*
X119313Y-131917D01*
X119693Y-132333D01*
X120200Y-132500D01*
X120707Y-132333D01*
X121087Y-131917D01*
X121340Y-131417D01*
X121530Y-130750D01*
X121593Y-130000D01*
X121530Y-129250D01*
X121340Y-128583D01*
X121087Y-128083D01*
X120707Y-127667D01*
X120200Y-127500D01*
G01X123907Y-131500D02*
X124287Y-132083D01*
X124793Y-132417D01*
X125363Y-132500D01*
X125870Y-132417D01*
X126377Y-132000D01*
X126693Y-131500D01*
X126757Y-131000D01*
X126630Y-130417D01*
X126187Y-130000D01*
X125743Y-129833D01*
X125173D01*
G01X125743D02*
X126123Y-129583D01*
X126440Y-129167D01*
X126567Y-128667D01*
X126440Y-128167D01*
X126123Y-127750D01*
X125553Y-127500D01*
X124983Y-127583D01*
X124413Y-127917D01*
G01X130717Y-134167D02*
X131350Y-133333D01*
X131667Y-132500D01*
Y-129167D01*
X131350Y-128333D01*
X130717Y-127500D01*
G01X134107Y-131500D02*
X134487Y-132083D01*
X134993Y-132417D01*
X135563Y-132500D01*
X136070Y-132417D01*
X136577Y-132000D01*
X136893Y-131500D01*
X136957Y-131000D01*
X136830Y-130417D01*
X136387Y-130000D01*
X135943Y-129833D01*
X135373D01*
G01X135943D02*
X136323Y-129583D01*
X136640Y-129167D01*
X136767Y-128667D01*
X136640Y-128167D01*
X136323Y-127750D01*
X135753Y-127500D01*
X135183Y-127583D01*
X134613Y-127917D01*
G01X139523Y-131917D02*
X139967Y-132333D01*
X140473Y-132500D01*
X140980Y-132333D01*
X141423Y-131833D01*
X141740Y-131083D01*
X141867Y-130333D01*
Y-129417D01*
X141740Y-128667D01*
X141423Y-128000D01*
X141043Y-127667D01*
X140600Y-127500D01*
X140093Y-127667D01*
X139713Y-128000D01*
X139460Y-128500D01*
X139333Y-129167D01*
X139460Y-129750D01*
X139777Y-130333D01*
X140157Y-130667D01*
X140600Y-130750D01*
X141107Y-130583D01*
X141487Y-130167D01*
X141867Y-129417D01*
G01X145573Y-132500D02*
X145700Y-131417D01*
X145890Y-130500D01*
X146143Y-129667D01*
X146460Y-128750D01*
X146967Y-127500D01*
X144433D01*
G01X149977Y-130833D02*
X151623D01*
G01X154507Y-131500D02*
X154887Y-132083D01*
X155393Y-132417D01*
X155963Y-132500D01*
X156470Y-132417D01*
X156977Y-132000D01*
X157293Y-131500D01*
X157357Y-131000D01*
X157230Y-130417D01*
X156787Y-130000D01*
X156343Y-129833D01*
X155773D01*
G01X156343D02*
X156723Y-129583D01*
X157040Y-129167D01*
X157167Y-128667D01*
X157040Y-128167D01*
X156723Y-127750D01*
X156153Y-127500D01*
X155583Y-127583D01*
X155013Y-127917D01*
G01X159797Y-130417D02*
X160240Y-129833D01*
X160620Y-129500D01*
X161127Y-129333D01*
X161570Y-129500D01*
X161887Y-129833D01*
X162140Y-130333D01*
X162203Y-130917D01*
X162140Y-131417D01*
X161887Y-131917D01*
X161507Y-132333D01*
X161063Y-132500D01*
X160557Y-132333D01*
X160113Y-131833D01*
X159860Y-131083D01*
X159797Y-130250D01*
X159923Y-129167D01*
X160113Y-128583D01*
X160430Y-128000D01*
X160873Y-127583D01*
X161317Y-127500D01*
X161760Y-127667D01*
X162077Y-128083D01*
G01X166100Y-132500D02*
Y-127500D01*
X165340Y-128500D01*
G01Y-132500D02*
X166860D01*
G01X171960D02*
Y-127500D01*
X169617Y-131083D01*
X172783D01*
G01X55105Y891587D02*
X61405D01*
Y893467D01*
X61090Y894094D01*
X60355Y894564D01*
X59515Y894721D01*
X58675Y894564D01*
X58045Y894172D01*
X57730Y893467D01*
Y891587D01*
G01X55105Y897887D02*
X61405D01*
Y899846D01*
X61090Y900472D01*
X60670Y900864D01*
X59830Y901021D01*
X58990Y900864D01*
X58465Y900394D01*
X58150Y899846D01*
Y897887D01*
G01Y899846D02*
X55105Y901021D01*
G01Y907321D02*
Y904187D01*
X61405D01*
Y907321D01*
G01X58360Y906067D02*
Y904187D01*
G01X55945Y910409D02*
X55420Y911036D01*
X55105Y911741D01*
Y912367D01*
X55420Y912994D01*
X55945Y913464D01*
X56680Y913699D01*
X57415Y913542D01*
X58045Y913151D01*
X58465Y912446D01*
X58675Y911506D01*
X59095Y910957D01*
X59830Y910722D01*
X60565Y910879D01*
X61090Y911271D01*
X61405Y911819D01*
Y912367D01*
X61195Y912916D01*
X60670Y913386D01*
G01X55945Y916709D02*
X55420Y917336D01*
X55105Y918041D01*
Y918667D01*
X55420Y919294D01*
X55945Y919764D01*
X56680Y919999D01*
X57415Y919842D01*
X58045Y919451D01*
X58465Y918746D01*
X58675Y917806D01*
X59095Y917257D01*
X59830Y917022D01*
X60565Y917179D01*
X61090Y917571D01*
X61405Y918119D01*
Y918667D01*
X61195Y919216D01*
X60670Y919686D01*
G01X55105Y935766D02*
X61405D01*
Y938742D01*
G01X58360Y937646D02*
Y935766D01*
G01X61405Y942614D02*
Y944494D01*
G01Y943554D02*
X55105D01*
G01Y942614D02*
Y944494D01*
G01X61405Y949854D02*
X55105D01*
G01X61405Y948052D02*
Y951656D01*
G01X68059Y1232921D02*
X74359D01*
Y1234801D01*
X74044Y1235428D01*
X73309Y1235898D01*
X72469Y1236055D01*
X71629Y1235898D01*
X70999Y1235506D01*
X70684Y1234801D01*
Y1232921D01*
G01X68059Y1239221D02*
X74359D01*
Y1241180D01*
X74044Y1241806D01*
X73624Y1242198D01*
X72784Y1242355D01*
X71944Y1242198D01*
X71419Y1241728D01*
X71104Y1241180D01*
Y1239221D01*
G01Y1241180D02*
X68059Y1242355D01*
G01Y1248655D02*
Y1245521D01*
X74359D01*
Y1248655D01*
G01X71314Y1247401D02*
Y1245521D01*
G01X68899Y1251743D02*
X68374Y1252370D01*
X68059Y1253075D01*
Y1253701D01*
X68374Y1254328D01*
X68899Y1254798D01*
X69634Y1255033D01*
X70369Y1254876D01*
X70999Y1254485D01*
X71419Y1253780D01*
X71629Y1252840D01*
X72049Y1252291D01*
X72784Y1252056D01*
X73519Y1252213D01*
X74044Y1252605D01*
X74359Y1253153D01*
Y1253701D01*
X74149Y1254250D01*
X73624Y1254720D01*
G01X68899Y1258043D02*
X68374Y1258670D01*
X68059Y1259375D01*
Y1260001D01*
X68374Y1260628D01*
X68899Y1261098D01*
X69634Y1261333D01*
X70369Y1261176D01*
X70999Y1260785D01*
X71419Y1260080D01*
X71629Y1259140D01*
X72049Y1258591D01*
X72784Y1258356D01*
X73519Y1258513D01*
X74044Y1258905D01*
X74359Y1259453D01*
Y1260001D01*
X74149Y1260550D01*
X73624Y1261020D01*
G01X68059Y1277100D02*
X74359D01*
Y1280076D01*
G01X71314Y1278980D02*
Y1277100D01*
G01X74359Y1283948D02*
Y1285828D01*
G01Y1284888D02*
X68059D01*
G01Y1283948D02*
Y1285828D01*
G01X74359Y1291188D02*
X68059D01*
G01X74359Y1289386D02*
Y1292990D01*
G01X191000Y-62500D02*
Y-137500D01*
G01Y-112500D02*
X294000D01*
Y-87500D01*
G01X191000D02*
X294000D01*
G01X301507Y-122500D02*
Y-117500D01*
X302773D01*
X303280Y-117750D01*
X303660Y-118083D01*
X303977Y-118583D01*
X304230Y-119167D01*
X304293Y-120000D01*
X304230Y-120833D01*
X303977Y-121417D01*
X303660Y-121917D01*
X303280Y-122250D01*
X302773Y-122500D01*
X301507D01*
G01X306417D02*
X308000Y-117500D01*
X309583Y-122500D01*
G01X309013Y-120750D02*
X306987D01*
G01X313100Y-117500D02*
Y-122500D01*
G01X311643Y-117500D02*
X314557D01*
G01X319467Y-122500D02*
X316933D01*
Y-117500D01*
X319467D01*
G01X318453Y-119917D02*
X316933D01*
G01X323300Y-122667D02*
X323173Y-122583D01*
Y-122417D01*
X323300Y-122333D01*
X323427Y-122417D01*
Y-122583D01*
X323300Y-122667D01*
G01Y-120417D02*
X323173Y-120333D01*
Y-120167D01*
X323300Y-120083D01*
X323427Y-120167D01*
Y-120333D01*
X323300Y-120417D01*
G01X296000Y-62500D02*
Y-137500D01*
G01X294000Y-62500D02*
Y-137500D01*
G01X301633Y-97500D02*
Y-92500D01*
X303153D01*
X303660Y-92750D01*
X304040Y-93333D01*
X304167Y-94000D01*
X304040Y-94667D01*
X303723Y-95167D01*
X303153Y-95417D01*
X301633D01*
G01X306860Y-97667D02*
X309140Y-92500D01*
G01X311643Y-97500D02*
Y-92500D01*
X314557Y-97500D01*
Y-92500D01*
G01X318200Y-97667D02*
X318073Y-97583D01*
Y-97417D01*
X318200Y-97333D01*
X318327Y-97417D01*
Y-97583D01*
X318200Y-97667D01*
G01Y-95417D02*
X318073Y-95333D01*
Y-95167D01*
X318200Y-95083D01*
X318327Y-95167D01*
Y-95333D01*
X318200Y-95417D01*
G01X296000Y-112500D02*
X496000D01*
G01X301633Y-72500D02*
Y-67500D01*
X303153D01*
X303660Y-67750D01*
X304040Y-68333D01*
X304167Y-69000D01*
X304040Y-69667D01*
X303723Y-70167D01*
X303153Y-70417D01*
X301633D01*
G01X306733Y-72500D02*
Y-67500D01*
X308317D01*
X308823Y-67750D01*
X309140Y-68083D01*
X309267Y-68750D01*
X309140Y-69417D01*
X308760Y-69833D01*
X308317Y-70083D01*
X306733D01*
G01X308317D02*
X309267Y-72500D01*
G01X313100D02*
X312593Y-72417D01*
X312150Y-72083D01*
X311770Y-71583D01*
X311517Y-71000D01*
X311390Y-70333D01*
Y-69667D01*
X311517Y-69000D01*
X311770Y-68417D01*
X312150Y-67917D01*
X312593Y-67583D01*
X313100Y-67500D01*
X313607Y-67583D01*
X314050Y-67917D01*
X314430Y-68417D01*
X314683Y-69000D01*
X314810Y-69667D01*
Y-70333D01*
X314683Y-71000D01*
X314430Y-71583D01*
X314050Y-72083D01*
X313607Y-72417D01*
X313100Y-72500D01*
G01X316933Y-71500D02*
X317250Y-72000D01*
X317630Y-72333D01*
X318073Y-72500D01*
X318580Y-72333D01*
X318960Y-72000D01*
X319340Y-71500D01*
X319467Y-70833D01*
Y-67500D01*
G01X324567Y-72500D02*
X322033D01*
Y-67500D01*
X324567D01*
G01X323553Y-69917D02*
X322033D01*
G01X329793Y-67917D02*
X329413Y-67667D01*
X328970Y-67500D01*
X328463D01*
X327893Y-67750D01*
X327450Y-68167D01*
X327133Y-68667D01*
X326880Y-69500D01*
X326817Y-70250D01*
X326943Y-71000D01*
X327133Y-71500D01*
X327513Y-72000D01*
X327957Y-72333D01*
X328400Y-72500D01*
X328843D01*
X329287Y-72333D01*
X329667Y-72083D01*
X329983Y-71750D01*
G01X333500Y-67500D02*
Y-72500D01*
G01X332043Y-67500D02*
X334957D01*
G01X338600Y-72667D02*
X338473Y-72583D01*
Y-72417D01*
X338600Y-72333D01*
X338727Y-72417D01*
Y-72583D01*
X338600Y-72667D01*
G01Y-70417D02*
X338473Y-70333D01*
Y-70167D01*
X338600Y-70083D01*
X338727Y-70167D01*
Y-70333D01*
X338600Y-70417D01*
G01X296000Y-87500D02*
X496000D01*
G01X317323Y1885039D02*
Y1881102D01*
G02X296850I-10237J0D01*
G01Y1885039D01*
G02X317323I10236J0D01*
G01X411000Y-112500D02*
Y-137500D01*
G01X416633Y-122500D02*
Y-117500D01*
X418217D01*
X418723Y-117750D01*
X419040Y-118083D01*
X419167Y-118750D01*
X419040Y-119417D01*
X418660Y-119833D01*
X418217Y-120083D01*
X416633D01*
G01X418217D02*
X419167Y-122500D01*
G01X424267D02*
X421733D01*
Y-117500D01*
X424267D01*
G01X423253Y-119917D02*
X421733D01*
G01X426517Y-117500D02*
X428100Y-122500D01*
X429683Y-117500D01*
G01X433200Y-122667D02*
X433073Y-122583D01*
Y-122417D01*
X433200Y-122333D01*
X433327Y-122417D01*
Y-122583D01*
X433200Y-122667D01*
G01Y-120417D02*
X433073Y-120333D01*
Y-120167D01*
X433200Y-120083D01*
X433327Y-120167D01*
Y-120333D01*
X433200Y-120417D01*
G01X460000Y-112500D02*
Y-137500D01*
G01X-723776Y2987387D02*
Y-376795D01*
Y-489221D01*
X1782976D01*
Y-376795D01*
Y2987387D01*
X-723776D01*
G01X47633Y1053821D02*
X-11619D01*
Y678900D01*
X47633D01*
Y1053821D01*
G01X16471Y690711D02*
X192D01*
Y1042010D01*
X35822D01*
G01X47637Y1412086D02*
X-11615D01*
Y1037165D01*
X47637D01*
Y1412086D01*
G01X16475Y1048976D02*
X196D01*
Y1400275D01*
X35826D01*
G01X6705Y-124160D02*
X7332Y-124685D01*
X8037Y-125000D01*
X8663D01*
X9290Y-124685D01*
X9760Y-124160D01*
X9995Y-123425D01*
X9838Y-122690D01*
X9447Y-122060D01*
X8742Y-121640D01*
X7802Y-121430D01*
X7253Y-121010D01*
X7018Y-120275D01*
X7175Y-119540D01*
X7567Y-119015D01*
X8115Y-118700D01*
X8663D01*
X9212Y-118910D01*
X9682Y-119435D01*
G01X13005Y-125000D02*
Y-118700D01*
G01X16295D02*
Y-125000D01*
G01Y-121850D02*
X13005D01*
G01X20010Y-118700D02*
X21890D01*
G01X20950D02*
Y-125000D01*
G01X20010D02*
X21890D01*
G01X28817D02*
X25683D01*
Y-118700D01*
X28817D01*
G01X27563Y-121745D02*
X25683D01*
G01X31748Y-125000D02*
Y-118700D01*
X35352Y-125000D01*
Y-118700D01*
G01X39693Y-126155D02*
X40007Y-124790D01*
G01X46150Y-118700D02*
Y-125000D01*
G01X44348Y-118700D02*
X47952D01*
G01X50492Y-125000D02*
X52450Y-118700D01*
X54408Y-125000D01*
G01X53703Y-122795D02*
X51197D01*
G01X57810Y-118700D02*
X59690D01*
G01X58750D02*
Y-125000D01*
G01X57810D02*
X59690D01*
G01X62700Y-118700D02*
X63797Y-125000D01*
X65050Y-118700D01*
X66303Y-125000D01*
X67400Y-118700D01*
G01X69392Y-125000D02*
X71350Y-118700D01*
X73308Y-125000D01*
G01X72603Y-122795D02*
X70097D01*
G01X75848Y-125000D02*
Y-118700D01*
X79452Y-125000D01*
Y-118700D01*
G01X88683Y-125000D02*
Y-118700D01*
X90642D01*
X91268Y-119015D01*
X91660Y-119435D01*
X91817Y-120275D01*
X91660Y-121115D01*
X91190Y-121640D01*
X90642Y-121955D01*
X88683D01*
G01X90642D02*
X91817Y-125000D01*
G01X96550Y-125210D02*
X96393Y-125105D01*
Y-124895D01*
X96550Y-124790D01*
X96707Y-124895D01*
Y-125105D01*
X96550Y-125210D01*
G01X102850Y-125000D02*
X102223Y-124895D01*
X101675Y-124475D01*
X101205Y-123845D01*
X100892Y-123110D01*
X100735Y-122270D01*
Y-121430D01*
X100892Y-120590D01*
X101205Y-119855D01*
X101675Y-119225D01*
X102223Y-118805D01*
X102850Y-118700D01*
X103477Y-118805D01*
X104025Y-119225D01*
X104495Y-119855D01*
X104808Y-120590D01*
X104965Y-121430D01*
Y-122270D01*
X104808Y-123110D01*
X104495Y-123845D01*
X104025Y-124475D01*
X103477Y-124895D01*
X102850Y-125000D01*
G01X109150Y-125210D02*
X108993Y-125105D01*
Y-124895D01*
X109150Y-124790D01*
X109307Y-124895D01*
Y-125105D01*
X109150Y-125210D01*
G01X117173Y-119225D02*
X116703Y-118910D01*
X116155Y-118700D01*
X115528D01*
X114823Y-119015D01*
X114275Y-119540D01*
X113883Y-120170D01*
X113570Y-121220D01*
X113492Y-122165D01*
X113648Y-123110D01*
X113883Y-123740D01*
X114353Y-124370D01*
X114902Y-124790D01*
X115450Y-125000D01*
X115998D01*
X116547Y-124790D01*
X117017Y-124475D01*
X117408Y-124055D01*
G01X121750Y-125210D02*
X121593Y-125105D01*
Y-124895D01*
X121750Y-124790D01*
X121907Y-124895D01*
Y-125105D01*
X121750Y-125210D01*
G01X6627Y-115000D02*
Y-108700D01*
G01X9603D02*
X6627Y-112585D01*
G01X10073Y-115000D02*
X7958Y-110800D01*
G01X12927Y-108700D02*
Y-113215D01*
X13240Y-114160D01*
X13867Y-114790D01*
X14650Y-115000D01*
X15433Y-114790D01*
X16060Y-114160D01*
X16373Y-113215D01*
Y-108700D01*
G01X22517Y-115000D02*
X19383D01*
Y-108700D01*
X22517D01*
G01X21263Y-111745D02*
X19383D01*
G01X26310Y-108700D02*
X28190D01*
G01X27250D02*
Y-115000D01*
G01X26310D02*
X28190D01*
G01X38205Y-114160D02*
X38832Y-114685D01*
X39537Y-115000D01*
X40163D01*
X40790Y-114685D01*
X41260Y-114160D01*
X41495Y-113425D01*
X41338Y-112690D01*
X40947Y-112060D01*
X40242Y-111640D01*
X39302Y-111430D01*
X38753Y-111010D01*
X38518Y-110275D01*
X38675Y-109540D01*
X39067Y-109015D01*
X39615Y-108700D01*
X40163D01*
X40712Y-108910D01*
X41182Y-109435D01*
G01X44505Y-115000D02*
Y-108700D01*
G01X47795D02*
Y-115000D01*
G01Y-111850D02*
X44505D01*
G01X50492Y-115000D02*
X52450Y-108700D01*
X54408Y-115000D01*
G01X53703Y-112795D02*
X51197D01*
G01X56948Y-115000D02*
Y-108700D01*
X60552Y-115000D01*
Y-108700D01*
G01X69705Y-115000D02*
Y-108700D01*
G01X72995D02*
Y-115000D01*
G01Y-111850D02*
X69705D01*
G01X76005Y-114160D02*
X76632Y-114685D01*
X77337Y-115000D01*
X77963D01*
X78590Y-114685D01*
X79060Y-114160D01*
X79295Y-113425D01*
X79138Y-112690D01*
X78747Y-112060D01*
X78042Y-111640D01*
X77102Y-111430D01*
X76553Y-111010D01*
X76318Y-110275D01*
X76475Y-109540D01*
X76867Y-109015D01*
X77415Y-108700D01*
X77963D01*
X78512Y-108910D01*
X78982Y-109435D01*
G01X83010Y-108700D02*
X84890D01*
G01X83950D02*
Y-115000D01*
G01X83010D02*
X84890D01*
G01X88292D02*
X90250Y-108700D01*
X92208Y-115000D01*
G01X91503Y-112795D02*
X88997D01*
G01X94748Y-115000D02*
Y-108700D01*
X98352Y-115000D01*
Y-108700D01*
G01X103320Y-111850D02*
X104887D01*
Y-113740D01*
X104417Y-114370D01*
X103868Y-114790D01*
X103085Y-115000D01*
X102302Y-114790D01*
X101753Y-114370D01*
X101283Y-113740D01*
X100970Y-113005D01*
X100813Y-112165D01*
Y-111430D01*
X100970Y-110800D01*
X101283Y-110065D01*
X101753Y-109435D01*
X102223Y-109015D01*
X102850Y-108700D01*
X103398D01*
X104025Y-108910D01*
X104495Y-109330D01*
G01X108993Y-116155D02*
X109307Y-114790D01*
G01X115450Y-108700D02*
Y-115000D01*
G01X113648Y-108700D02*
X117252D01*
G01X119792Y-115000D02*
X121750Y-108700D01*
X123708Y-115000D01*
G01X123003Y-112795D02*
X120497D01*
G01X128050Y-115000D02*
X127423Y-114895D01*
X126875Y-114475D01*
X126405Y-113845D01*
X126092Y-113110D01*
X125935Y-112270D01*
Y-111430D01*
X126092Y-110590D01*
X126405Y-109855D01*
X126875Y-109225D01*
X127423Y-108805D01*
X128050Y-108700D01*
X128677Y-108805D01*
X129225Y-109225D01*
X129695Y-109855D01*
X130008Y-110590D01*
X130165Y-111430D01*
Y-112270D01*
X130008Y-113110D01*
X129695Y-113845D01*
X129225Y-114475D01*
X128677Y-114895D01*
X128050Y-115000D01*
G01X140650D02*
Y-112165D01*
X139083Y-108700D01*
G01X142217D02*
X140650Y-112165D01*
G01X145227Y-108700D02*
Y-113215D01*
X145540Y-114160D01*
X146167Y-114790D01*
X146950Y-115000D01*
X147733Y-114790D01*
X148360Y-114160D01*
X148673Y-113215D01*
Y-108700D01*
G01X151292Y-115000D02*
X153250Y-108700D01*
X155208Y-115000D01*
G01X154503Y-112795D02*
X151997D01*
G01X157748Y-115000D02*
Y-108700D01*
X161352Y-115000D01*
Y-108700D01*
G01X30650Y-92300D02*
X28130Y-91883D01*
X25925Y-90217D01*
X24035Y-87717D01*
X22775Y-84800D01*
X22145Y-81467D01*
Y-78133D01*
X22775Y-74800D01*
X24035Y-71883D01*
X25925Y-69384D01*
X28130Y-67717D01*
X30650Y-67300D01*
X33170Y-67717D01*
X35375Y-69384D01*
X37265Y-71883D01*
X38525Y-74800D01*
X39155Y-78133D01*
Y-81467D01*
X38525Y-84800D01*
X37265Y-87717D01*
X35375Y-90217D01*
X33170Y-91883D01*
X30650Y-92300D01*
G01X33170Y-85633D02*
X36950Y-92300D01*
G01X50495Y-75634D02*
Y-87300D01*
X51755Y-90217D01*
X53645Y-91883D01*
X55850Y-92300D01*
X58055Y-91883D01*
X59945Y-90217D01*
X61205Y-87300D01*
G01Y-92300D02*
Y-75634D01*
G01X86720Y-92300D02*
Y-75634D01*
G01Y-78550D02*
X85460Y-76884D01*
X83570Y-76050D01*
X81365Y-75634D01*
X79160Y-76467D01*
X77270Y-78133D01*
X76010Y-80634D01*
X75380Y-83967D01*
X76010Y-87300D01*
X77270Y-89801D01*
X79160Y-91467D01*
X81365Y-92300D01*
X83570Y-91883D01*
X85460Y-90634D01*
X86720Y-88967D01*
G01X100895Y-92300D02*
Y-75634D01*
G01Y-79800D02*
X102155Y-77717D01*
X104045Y-76050D01*
X106565Y-75634D01*
X108770Y-76050D01*
X110660Y-77717D01*
X111605Y-80634D01*
Y-92300D01*
G01X131450Y-67300D02*
Y-92300D01*
G01X127040Y-75634D02*
X135860D01*
G01X162320Y-92300D02*
Y-75634D01*
G01Y-78550D02*
X161060Y-76884D01*
X159170Y-76050D01*
X156965Y-75634D01*
X154760Y-76467D01*
X152870Y-78133D01*
X151610Y-80634D01*
X150980Y-83967D01*
X151610Y-87300D01*
X152870Y-89801D01*
X154760Y-91467D01*
X156965Y-92300D01*
X159170Y-91883D01*
X161060Y-90634D01*
X162320Y-88967D01*
G01X6548Y-105000D02*
Y-98700D01*
X10152Y-105000D01*
Y-98700D01*
G01X14650Y-105000D02*
X14023Y-104895D01*
X13475Y-104475D01*
X13005Y-103845D01*
X12692Y-103110D01*
X12535Y-102270D01*
Y-101430D01*
X12692Y-100590D01*
X13005Y-99855D01*
X13475Y-99225D01*
X14023Y-98805D01*
X14650Y-98700D01*
X15277Y-98805D01*
X15825Y-99225D01*
X16295Y-99855D01*
X16608Y-100590D01*
X16765Y-101430D01*
Y-102270D01*
X16608Y-103110D01*
X16295Y-103845D01*
X15825Y-104475D01*
X15277Y-104895D01*
X14650Y-105000D01*
G01X20950Y-105210D02*
X20793Y-105105D01*
Y-104895D01*
X20950Y-104790D01*
X21107Y-104895D01*
Y-105105D01*
X20950Y-105210D01*
G01X27250Y-105000D02*
Y-98700D01*
X26310Y-99960D01*
G01Y-105000D02*
X28190D01*
G01X33550D02*
X34098Y-104895D01*
X34725Y-104580D01*
X35117Y-104055D01*
X35273Y-103320D01*
X35117Y-102585D01*
X34647Y-101955D01*
X33942Y-101640D01*
X33158D01*
X32688Y-101430D01*
X32297Y-100905D01*
X32140Y-100170D01*
X32375Y-99435D01*
X32923Y-98910D01*
X33550Y-98700D01*
X34177Y-98910D01*
X34725Y-99435D01*
X34960Y-100170D01*
X34803Y-100905D01*
X34412Y-101430D01*
X33942Y-101640D01*
X33158D01*
X32453Y-101955D01*
X31983Y-102585D01*
X31827Y-103320D01*
X31983Y-104055D01*
X32375Y-104580D01*
X33002Y-104895D01*
X33550Y-105000D01*
G01X39850D02*
X40398Y-104895D01*
X41025Y-104580D01*
X41417Y-104055D01*
X41573Y-103320D01*
X41417Y-102585D01*
X40947Y-101955D01*
X40242Y-101640D01*
X39458D01*
X38988Y-101430D01*
X38597Y-100905D01*
X38440Y-100170D01*
X38675Y-99435D01*
X39223Y-98910D01*
X39850Y-98700D01*
X40477Y-98910D01*
X41025Y-99435D01*
X41260Y-100170D01*
X41103Y-100905D01*
X40712Y-101430D01*
X40242Y-101640D01*
X39458D01*
X38753Y-101955D01*
X38283Y-102585D01*
X38127Y-103320D01*
X38283Y-104055D01*
X38675Y-104580D01*
X39302Y-104895D01*
X39850Y-105000D01*
G01X45993Y-106155D02*
X46307Y-104790D01*
G01X50100Y-98700D02*
X51197Y-105000D01*
X52450Y-98700D01*
X53703Y-105000D01*
X54800Y-98700D01*
G01X60317Y-105000D02*
X57183D01*
Y-98700D01*
X60317D01*
G01X59063Y-101745D02*
X57183D01*
G01X63248Y-105000D02*
Y-98700D01*
X66852Y-105000D01*
Y-98700D01*
G01X76005Y-105000D02*
Y-98700D01*
G01X79295D02*
Y-105000D01*
G01Y-101850D02*
X76005D01*
G01X81600Y-98700D02*
X82697Y-105000D01*
X83950Y-98700D01*
X85203Y-105000D01*
X86300Y-98700D01*
G01X88292Y-105000D02*
X90250Y-98700D01*
X92208Y-105000D01*
G01X91503Y-102795D02*
X88997D01*
G01X101362Y-99750D02*
X101832Y-99120D01*
X102380Y-98805D01*
X103007Y-98700D01*
X103790Y-98910D01*
X104338Y-99435D01*
X104495Y-100065D01*
X104417Y-100695D01*
X104103Y-101220D01*
X102537Y-102270D01*
X101832Y-103005D01*
X101362Y-104055D01*
X101205Y-105000D01*
X104495D01*
G01X107348D02*
Y-98700D01*
X110952Y-105000D01*
Y-98700D01*
G01X113727Y-105000D02*
Y-98700D01*
X115293D01*
X115920Y-99015D01*
X116390Y-99435D01*
X116782Y-100065D01*
X117095Y-100800D01*
X117173Y-101850D01*
X117095Y-102900D01*
X116782Y-103635D01*
X116390Y-104265D01*
X115920Y-104685D01*
X115293Y-105000D01*
X113727D01*
G01X126483D02*
Y-98700D01*
X128442D01*
X129068Y-99015D01*
X129460Y-99435D01*
X129617Y-100275D01*
X129460Y-101115D01*
X128990Y-101640D01*
X128442Y-101955D01*
X126483D01*
G01X128442D02*
X129617Y-105000D01*
G01X132627D02*
Y-98700D01*
X134193D01*
X134820Y-99015D01*
X135290Y-99435D01*
X135682Y-100065D01*
X135995Y-100800D01*
X136073Y-101850D01*
X135995Y-102900D01*
X135682Y-103635D01*
X135290Y-104265D01*
X134820Y-104685D01*
X134193Y-105000D01*
X132627D01*
G01X140650Y-105210D02*
X140493Y-105105D01*
Y-104895D01*
X140650Y-104790D01*
X140807Y-104895D01*
Y-105105D01*
X140650Y-105210D01*
G01X13166Y25176D02*
X12898Y25228D01*
X12591Y25383D01*
X12399Y25641D01*
X12323Y26003D01*
X12399Y26364D01*
X12629Y26674D01*
X12974Y26829D01*
X13358D01*
X13588Y26933D01*
X13779Y27191D01*
X13856Y27553D01*
X13741Y27914D01*
X13473Y28173D01*
X13166Y28276D01*
X12859Y28173D01*
X12591Y27914D01*
X12476Y27553D01*
X12553Y27191D01*
X12744Y26933D01*
X12974Y26829D01*
X13358D01*
X13703Y26674D01*
X13933Y26364D01*
X14009Y26003D01*
X13933Y25641D01*
X13741Y25383D01*
X13434Y25228D01*
X13166Y25176D01*
G01X18243Y35576D02*
X18166Y36248D01*
X18051Y36816D01*
X17898Y37333D01*
X17706Y37901D01*
X17399Y38676D01*
X18933D01*
G01X123254Y114960D02*
G03I-57900J0D01*
G01X12635Y205243D02*
Y208343D01*
X13095Y207723D01*
G01Y205243D02*
X12175D01*
G01X18463Y218326D02*
X18233Y218636D01*
X17965Y218791D01*
X17658Y218843D01*
X17275Y218740D01*
X17007Y218481D01*
X16930Y218171D01*
X16968Y217861D01*
X17122Y217603D01*
X17888Y217086D01*
X18233Y216725D01*
X18463Y216208D01*
X18540Y215743D01*
X16930D01*
G01X17454Y242723D02*
X17377Y243395D01*
X17262Y243963D01*
X17109Y244480D01*
X16917Y245048D01*
X16610Y245823D01*
X18144D01*
G01X12377Y232323D02*
X12109Y232375D01*
X11802Y232530D01*
X11610Y232788D01*
X11534Y233150D01*
X11610Y233511D01*
X11840Y233821D01*
X12185Y233976D01*
X12569D01*
X12799Y234080D01*
X12990Y234338D01*
X13067Y234700D01*
X12952Y235061D01*
X12684Y235320D01*
X12377Y235423D01*
X12070Y235320D01*
X11802Y235061D01*
X11687Y234700D01*
X11764Y234338D01*
X11955Y234080D01*
X12185Y233976D01*
X12569D01*
X12914Y233821D01*
X13144Y233511D01*
X13220Y233150D01*
X13144Y232788D01*
X12952Y232530D01*
X12645Y232375D01*
X12377Y232323D01*
G01X12635Y414101D02*
Y417201D01*
X13095Y416581D01*
G01Y414101D02*
X12175D01*
G01X123254Y464960D02*
G03I-57900J0D01*
G01X18463Y427184D02*
X18233Y427494D01*
X17965Y427649D01*
X17658Y427701D01*
X17275Y427598D01*
X17007Y427339D01*
X16930Y427029D01*
X16968Y426719D01*
X17122Y426461D01*
X17888Y425944D01*
X18233Y425583D01*
X18463Y425066D01*
X18540Y424601D01*
X16930D01*
G01X13619Y507177D02*
X13351Y507229D01*
X13044Y507384D01*
X12852Y507642D01*
X12776Y508004D01*
X12852Y508365D01*
X13082Y508675D01*
X13427Y508830D01*
X13811D01*
X14041Y508934D01*
X14232Y509192D01*
X14309Y509554D01*
X14194Y509915D01*
X13926Y510174D01*
X13619Y510277D01*
X13312Y510174D01*
X13044Y509915D01*
X12929Y509554D01*
X13006Y509192D01*
X13197Y508934D01*
X13427Y508830D01*
X13811D01*
X14156Y508675D01*
X14386Y508365D01*
X14462Y508004D01*
X14386Y507642D01*
X14194Y507384D01*
X13887Y507229D01*
X13619Y507177D01*
G01X18646Y517277D02*
X18569Y517949D01*
X18454Y518517D01*
X18301Y519034D01*
X18109Y519602D01*
X17802Y520377D01*
X19336D01*
G01X11006Y604701D02*
X7906D01*
X8526Y605161D01*
G01X11006D02*
Y604241D01*
G01X16297Y605429D02*
X15987Y605199D01*
X15832Y604931D01*
X15780Y604624D01*
X15883Y604241D01*
X16142Y603973D01*
X16452Y603896D01*
X16762Y603934D01*
X17020Y604088D01*
X17537Y604854D01*
X17898Y605199D01*
X18415Y605429D01*
X18880Y605506D01*
Y603896D01*
G01X11006Y632064D02*
X7906D01*
X8526Y632524D01*
G01X11006D02*
Y631604D01*
G01X16297Y632792D02*
X15987Y632562D01*
X15832Y632294D01*
X15780Y631987D01*
X15883Y631604D01*
X16142Y631336D01*
X16452Y631259D01*
X16762Y631297D01*
X17020Y631451D01*
X17537Y632217D01*
X17898Y632562D01*
X18415Y632792D01*
X18880Y632869D01*
Y631259D01*
G01X13166Y699020D02*
X13321Y699173D01*
X13580Y699288D01*
X13941Y699365D01*
X14251Y699288D01*
X14458Y699135D01*
X14613Y698866D01*
Y697831D01*
X11513D01*
Y699096D01*
X11720Y699365D01*
X12030Y699518D01*
X12391Y699595D01*
X12753Y699518D01*
X13063Y699288D01*
X13166Y699020D01*
Y697831D01*
G01X11513Y701813D02*
X11565Y702081D01*
X11720Y702388D01*
X11978Y702580D01*
X12340Y702656D01*
X12701Y702580D01*
X13011Y702350D01*
X13166Y702005D01*
Y701621D01*
X13270Y701391D01*
X13528Y701200D01*
X13890Y701123D01*
X14251Y701238D01*
X14510Y701506D01*
X14613Y701813D01*
X14510Y702120D01*
X14251Y702388D01*
X13890Y702503D01*
X13528Y702426D01*
X13270Y702235D01*
X13166Y702005D01*
Y701621D01*
X13011Y701276D01*
X12701Y701046D01*
X12340Y700970D01*
X11978Y701046D01*
X11720Y701238D01*
X11565Y701545D01*
X11513Y701813D01*
G01Y704913D02*
X14613D01*
X13993Y704453D01*
G01X11513D02*
Y705373D01*
G01X8078Y693508D02*
X8233Y693661D01*
X8492Y693776D01*
X8853Y693853D01*
X9163Y693776D01*
X9370Y693623D01*
X9525Y693354D01*
Y692319D01*
X6425D01*
Y693584D01*
X6632Y693853D01*
X6942Y694006D01*
X7303Y694083D01*
X7665Y694006D01*
X7975Y693776D01*
X8078Y693508D01*
Y692319D01*
G01X6425Y696301D02*
X6477Y696569D01*
X6632Y696876D01*
X6890Y697068D01*
X7252Y697144D01*
X7613Y697068D01*
X7923Y696838D01*
X8078Y696493D01*
Y696109D01*
X8182Y695879D01*
X8440Y695688D01*
X8802Y695611D01*
X9163Y695726D01*
X9422Y695994D01*
X9525Y696301D01*
X9422Y696608D01*
X9163Y696876D01*
X8802Y696991D01*
X8440Y696914D01*
X8182Y696723D01*
X8078Y696493D01*
Y696109D01*
X7923Y695764D01*
X7613Y695534D01*
X7252Y695458D01*
X6890Y695534D01*
X6632Y695726D01*
X6477Y696033D01*
X6425Y696301D01*
G01X9008Y698673D02*
X9318Y698903D01*
X9473Y699171D01*
X9525Y699478D01*
X9422Y699861D01*
X9163Y700129D01*
X8853Y700206D01*
X8543Y700168D01*
X8285Y700014D01*
X7768Y699248D01*
X7407Y698903D01*
X6890Y698673D01*
X6425Y698596D01*
Y700206D01*
G01X35822Y1042010D02*
Y690711D01*
X24071D01*
G01X123254Y814960D02*
G03I-57900J0D01*
G01X24355Y1033805D02*
X27455Y1034763D01*
X24355Y1035721D01*
G01X25440Y1035376D02*
Y1034150D01*
G01X24355Y1037863D02*
X27455D01*
X26835Y1037403D01*
G01X24355D02*
Y1038323D01*
G01X16166Y1035070D02*
X16321Y1035223D01*
X16580Y1035338D01*
X16941Y1035415D01*
X17251Y1035338D01*
X17458Y1035185D01*
X17613Y1034916D01*
Y1033881D01*
X14513D01*
Y1035146D01*
X14720Y1035415D01*
X15030Y1035568D01*
X15391Y1035645D01*
X15753Y1035568D01*
X16063Y1035338D01*
X16166Y1035070D01*
Y1033881D01*
G01X14513Y1037863D02*
X17613D01*
X16993Y1037403D01*
G01X14513D02*
Y1038323D01*
G01X7794Y1033876D02*
X7949Y1034029D01*
X8208Y1034144D01*
X8569Y1034221D01*
X8879Y1034144D01*
X9086Y1033991D01*
X9241Y1033722D01*
Y1032687D01*
X6141D01*
Y1033952D01*
X6348Y1034221D01*
X6658Y1034374D01*
X7019Y1034451D01*
X7381Y1034374D01*
X7691Y1034144D01*
X7794Y1033876D01*
Y1032687D01*
G01X8724Y1035941D02*
X9034Y1036171D01*
X9189Y1036439D01*
X9241Y1036746D01*
X9138Y1037129D01*
X8879Y1037397D01*
X8569Y1037474D01*
X8259Y1037436D01*
X8001Y1037282D01*
X7484Y1036516D01*
X7123Y1036171D01*
X6606Y1035941D01*
X6141Y1035864D01*
Y1037474D01*
G01X13170Y1057285D02*
X13325Y1057438D01*
X13584Y1057553D01*
X13945Y1057630D01*
X14255Y1057553D01*
X14462Y1057400D01*
X14617Y1057131D01*
Y1056096D01*
X11517D01*
Y1057361D01*
X11724Y1057630D01*
X12034Y1057783D01*
X12395Y1057860D01*
X12757Y1057783D01*
X13067Y1057553D01*
X13170Y1057285D01*
Y1056096D01*
G01X11517Y1060078D02*
X11569Y1060346D01*
X11724Y1060653D01*
X11982Y1060845D01*
X12344Y1060921D01*
X12705Y1060845D01*
X13015Y1060615D01*
X13170Y1060270D01*
Y1059886D01*
X13274Y1059656D01*
X13532Y1059465D01*
X13894Y1059388D01*
X14255Y1059503D01*
X14514Y1059771D01*
X14617Y1060078D01*
X14514Y1060385D01*
X14255Y1060653D01*
X13894Y1060768D01*
X13532Y1060691D01*
X13274Y1060500D01*
X13170Y1060270D01*
Y1059886D01*
X13015Y1059541D01*
X12705Y1059311D01*
X12344Y1059235D01*
X11982Y1059311D01*
X11724Y1059503D01*
X11569Y1059810D01*
X11517Y1060078D01*
G01Y1063178D02*
X14617D01*
X13997Y1062718D01*
G01X11517D02*
Y1063638D01*
G01X8296Y1051285D02*
X8451Y1051438D01*
X8710Y1051553D01*
X9071Y1051630D01*
X9381Y1051553D01*
X9588Y1051400D01*
X9743Y1051131D01*
Y1050096D01*
X6643D01*
Y1051361D01*
X6850Y1051630D01*
X7160Y1051783D01*
X7521Y1051860D01*
X7883Y1051783D01*
X8193Y1051553D01*
X8296Y1051285D01*
Y1050096D01*
G01X6643Y1054078D02*
X6695Y1054346D01*
X6850Y1054653D01*
X7108Y1054845D01*
X7470Y1054921D01*
X7831Y1054845D01*
X8141Y1054615D01*
X8296Y1054270D01*
Y1053886D01*
X8400Y1053656D01*
X8658Y1053465D01*
X9020Y1053388D01*
X9381Y1053503D01*
X9640Y1053771D01*
X9743Y1054078D01*
X9640Y1054385D01*
X9381Y1054653D01*
X9020Y1054768D01*
X8658Y1054691D01*
X8400Y1054500D01*
X8296Y1054270D01*
Y1053886D01*
X8141Y1053541D01*
X7831Y1053311D01*
X7470Y1053235D01*
X7108Y1053311D01*
X6850Y1053503D01*
X6695Y1053810D01*
X6643Y1054078D01*
G01X9226Y1056450D02*
X9536Y1056680D01*
X9691Y1056948D01*
X9743Y1057255D01*
X9640Y1057638D01*
X9381Y1057906D01*
X9071Y1057983D01*
X8761Y1057945D01*
X8503Y1057791D01*
X7986Y1057025D01*
X7625Y1056680D01*
X7108Y1056450D01*
X6643Y1056373D01*
Y1057983D01*
G01X35826Y1400275D02*
Y1048976D01*
X24075D01*
G01X123254Y1164960D02*
G03I-57900J0D01*
G01X24359Y1392070D02*
X27459Y1393028D01*
X24359Y1393986D01*
G01X25444Y1393641D02*
Y1392415D01*
G01X24359Y1396128D02*
X27459D01*
X26839Y1395668D01*
G01X24359D02*
Y1396588D01*
G01X16170Y1393335D02*
X16325Y1393488D01*
X16584Y1393603D01*
X16945Y1393680D01*
X17255Y1393603D01*
X17462Y1393450D01*
X17617Y1393181D01*
Y1392146D01*
X14517D01*
Y1393411D01*
X14724Y1393680D01*
X15034Y1393833D01*
X15395Y1393910D01*
X15757Y1393833D01*
X16067Y1393603D01*
X16170Y1393335D01*
Y1392146D01*
G01X14517Y1396128D02*
X17617D01*
X16997Y1395668D01*
G01X14517D02*
Y1396588D01*
G01X8296Y1388835D02*
X8451Y1388988D01*
X8710Y1389103D01*
X9071Y1389180D01*
X9381Y1389103D01*
X9588Y1388950D01*
X9743Y1388681D01*
Y1387646D01*
X6643D01*
Y1388911D01*
X6850Y1389180D01*
X7160Y1389333D01*
X7521Y1389410D01*
X7883Y1389333D01*
X8193Y1389103D01*
X8296Y1388835D01*
Y1387646D01*
G01X9226Y1390900D02*
X9536Y1391130D01*
X9691Y1391398D01*
X9743Y1391705D01*
X9640Y1392088D01*
X9381Y1392356D01*
X9071Y1392433D01*
X8761Y1392395D01*
X8503Y1392241D01*
X7986Y1391475D01*
X7625Y1391130D01*
X7108Y1390900D01*
X6643Y1390823D01*
Y1392433D01*
G01X123254Y1514960D02*
G03I-57900J0D01*
G01X11006Y1476749D02*
X7906D01*
X8526Y1477209D01*
G01X11006D02*
Y1476289D01*
G01X16297Y1477477D02*
X15987Y1477247D01*
X15832Y1476979D01*
X15780Y1476672D01*
X15883Y1476289D01*
X16142Y1476021D01*
X16452Y1475944D01*
X16762Y1475982D01*
X17020Y1476136D01*
X17537Y1476902D01*
X17898Y1477247D01*
X18415Y1477477D01*
X18880Y1477554D01*
Y1475944D01*
G01X11006Y1504111D02*
X7906D01*
X8526Y1504571D01*
G01X11006D02*
Y1503651D01*
G01X16297Y1504839D02*
X15987Y1504609D01*
X15832Y1504341D01*
X15780Y1504034D01*
X15883Y1503651D01*
X16142Y1503383D01*
X16452Y1503306D01*
X16762Y1503344D01*
X17020Y1503498D01*
X17537Y1504264D01*
X17898Y1504609D01*
X18415Y1504839D01*
X18880Y1504916D01*
Y1503306D01*
G01X14345Y1611809D02*
Y1614909D01*
X14805Y1614289D01*
G01Y1611809D02*
X13885D01*
G01X19473Y1624542D02*
X19243Y1624852D01*
X18975Y1625007D01*
X18668Y1625059D01*
X18285Y1624956D01*
X18017Y1624697D01*
X17940Y1624387D01*
X17978Y1624077D01*
X18132Y1623819D01*
X18898Y1623302D01*
X19243Y1622941D01*
X19473Y1622424D01*
X19550Y1621959D01*
X17940D01*
G01X24566Y1659034D02*
X24876Y1659264D01*
X25031Y1659532D01*
X25083Y1659839D01*
X24980Y1660222D01*
X24721Y1660490D01*
X24411Y1660567D01*
X24101Y1660529D01*
X23843Y1660375D01*
X23326Y1659609D01*
X22965Y1659264D01*
X22448Y1659034D01*
X21983Y1658957D01*
Y1660567D01*
G01X25083Y1662862D02*
X24980Y1662555D01*
X24721Y1662325D01*
X24411Y1662172D01*
X23998Y1662057D01*
X23533Y1662019D01*
X23068Y1662057D01*
X22655Y1662172D01*
X22345Y1662325D01*
X22086Y1662555D01*
X21983Y1662862D01*
X22086Y1663169D01*
X22345Y1663399D01*
X22655Y1663552D01*
X23068Y1663667D01*
X23533Y1663705D01*
X23998Y1663667D01*
X24411Y1663552D01*
X24721Y1663399D01*
X24980Y1663169D01*
X25083Y1662862D01*
G01X123254Y1864960D02*
G03I-57900J0D01*
G01X25667Y1825821D02*
X22567D01*
X23187Y1826281D01*
G01X25667D02*
Y1825361D01*
G01Y1822721D02*
X22567D01*
X23187Y1823181D01*
G01X25667D02*
Y1822261D01*
G01X12635Y1945558D02*
Y1948658D01*
X13095Y1948038D01*
G01Y1945558D02*
X12175D01*
G01X18463Y1958641D02*
X18233Y1958951D01*
X17965Y1959106D01*
X17658Y1959158D01*
X17275Y1959055D01*
X17007Y1958796D01*
X16930Y1958486D01*
X16968Y1958176D01*
X17122Y1957918D01*
X17888Y1957401D01*
X18233Y1957040D01*
X18463Y1956523D01*
X18540Y1956058D01*
X16930D01*
G01X12635Y2049928D02*
Y2053028D01*
X13095Y2052408D01*
G01Y2049928D02*
X12175D01*
G01X18463Y2063011D02*
X18233Y2063321D01*
X17965Y2063476D01*
X17658Y2063528D01*
X17275Y2063425D01*
X17007Y2063166D01*
X16930Y2062856D01*
X16968Y2062546D01*
X17122Y2062288D01*
X17888Y2061771D01*
X18233Y2061410D01*
X18463Y2060893D01*
X18540Y2060428D01*
X16930D01*
G01X32230Y691755D02*
X35330Y692713D01*
X32230Y693671D01*
G01X33315Y693326D02*
Y692100D01*
G01X32230Y695813D02*
X32282Y696081D01*
X32437Y696388D01*
X32695Y696580D01*
X33057Y696656D01*
X33418Y696580D01*
X33728Y696350D01*
X33883Y696005D01*
Y695621D01*
X33987Y695391D01*
X34245Y695200D01*
X34607Y695123D01*
X34968Y695238D01*
X35227Y695506D01*
X35330Y695813D01*
X35227Y696120D01*
X34968Y696388D01*
X34607Y696503D01*
X34245Y696426D01*
X33987Y696235D01*
X33883Y696005D01*
Y695621D01*
X33728Y695276D01*
X33418Y695046D01*
X33057Y694970D01*
X32695Y695046D01*
X32437Y695238D01*
X32282Y695545D01*
X32230Y695813D01*
G01X34813Y698185D02*
X35123Y698415D01*
X35278Y698683D01*
X35330Y698990D01*
X35227Y699373D01*
X34968Y699641D01*
X34658Y699718D01*
X34348Y699680D01*
X34090Y699526D01*
X33573Y698760D01*
X33212Y698415D01*
X32695Y698185D01*
X32230Y698108D01*
Y699718D01*
G01X26605Y697755D02*
X29705Y698713D01*
X26605Y699671D01*
G01X27690Y699326D02*
Y698100D01*
G01X26605Y701813D02*
X26657Y702081D01*
X26812Y702388D01*
X27070Y702580D01*
X27432Y702656D01*
X27793Y702580D01*
X28103Y702350D01*
X28258Y702005D01*
Y701621D01*
X28362Y701391D01*
X28620Y701200D01*
X28982Y701123D01*
X29343Y701238D01*
X29602Y701506D01*
X29705Y701813D01*
X29602Y702120D01*
X29343Y702388D01*
X28982Y702503D01*
X28620Y702426D01*
X28362Y702235D01*
X28258Y702005D01*
Y701621D01*
X28103Y701276D01*
X27793Y701046D01*
X27432Y700970D01*
X27070Y701046D01*
X26812Y701238D01*
X26657Y701545D01*
X26605Y701813D01*
G01Y704913D02*
X29705D01*
X29085Y704453D01*
G01X26605D02*
Y705373D01*
G01X31797Y1031230D02*
X34897Y1032188D01*
X31797Y1033146D01*
G01X32882Y1032801D02*
Y1031575D01*
G01X34380Y1034560D02*
X34690Y1034790D01*
X34845Y1035058D01*
X34897Y1035365D01*
X34794Y1035748D01*
X34535Y1036016D01*
X34225Y1036093D01*
X33915Y1036055D01*
X33657Y1035901D01*
X33140Y1035135D01*
X32779Y1034790D01*
X32262Y1034560D01*
X31797Y1034483D01*
Y1036093D01*
G01X32234Y1050020D02*
X35334Y1050978D01*
X32234Y1051936D01*
G01X33319Y1051591D02*
Y1050365D01*
G01X32234Y1054078D02*
X32286Y1054346D01*
X32441Y1054653D01*
X32699Y1054845D01*
X33061Y1054921D01*
X33422Y1054845D01*
X33732Y1054615D01*
X33887Y1054270D01*
Y1053886D01*
X33991Y1053656D01*
X34249Y1053465D01*
X34611Y1053388D01*
X34972Y1053503D01*
X35231Y1053771D01*
X35334Y1054078D01*
X35231Y1054385D01*
X34972Y1054653D01*
X34611Y1054768D01*
X34249Y1054691D01*
X33991Y1054500D01*
X33887Y1054270D01*
Y1053886D01*
X33732Y1053541D01*
X33422Y1053311D01*
X33061Y1053235D01*
X32699Y1053311D01*
X32441Y1053503D01*
X32286Y1053810D01*
X32234Y1054078D01*
G01X34817Y1056450D02*
X35127Y1056680D01*
X35282Y1056948D01*
X35334Y1057255D01*
X35231Y1057638D01*
X34972Y1057906D01*
X34662Y1057983D01*
X34352Y1057945D01*
X34094Y1057791D01*
X33577Y1057025D01*
X33216Y1056680D01*
X32699Y1056450D01*
X32234Y1056373D01*
Y1057983D01*
G01X26609Y1056020D02*
X29709Y1056978D01*
X26609Y1057936D01*
G01X27694Y1057591D02*
Y1056365D01*
G01X26609Y1060078D02*
X26661Y1060346D01*
X26816Y1060653D01*
X27074Y1060845D01*
X27436Y1060921D01*
X27797Y1060845D01*
X28107Y1060615D01*
X28262Y1060270D01*
Y1059886D01*
X28366Y1059656D01*
X28624Y1059465D01*
X28986Y1059388D01*
X29347Y1059503D01*
X29606Y1059771D01*
X29709Y1060078D01*
X29606Y1060385D01*
X29347Y1060653D01*
X28986Y1060768D01*
X28624Y1060691D01*
X28366Y1060500D01*
X28262Y1060270D01*
Y1059886D01*
X28107Y1059541D01*
X27797Y1059311D01*
X27436Y1059235D01*
X27074Y1059311D01*
X26816Y1059503D01*
X26661Y1059810D01*
X26609Y1060078D01*
G01Y1063178D02*
X29709D01*
X29089Y1062718D01*
G01X26609D02*
Y1063638D01*
G01X32234Y1387570D02*
X35334Y1388528D01*
X32234Y1389486D01*
G01X33319Y1389141D02*
Y1387915D01*
G01X34817Y1390900D02*
X35127Y1391130D01*
X35282Y1391398D01*
X35334Y1391705D01*
X35231Y1392088D01*
X34972Y1392356D01*
X34662Y1392433D01*
X34352Y1392395D01*
X34094Y1392241D01*
X33577Y1391475D01*
X33216Y1391130D01*
X32699Y1390900D01*
X32234Y1390823D01*
Y1392433D01*
G01X43036Y1659981D02*
X46136D01*
X45516Y1659521D01*
G01X43036D02*
Y1660441D01*
G01X46136Y1663081D02*
X46033Y1662774D01*
X45774Y1662544D01*
X45464Y1662391D01*
X45051Y1662276D01*
X44586Y1662238D01*
X44121Y1662276D01*
X43708Y1662391D01*
X43398Y1662544D01*
X43139Y1662774D01*
X43036Y1663081D01*
X43139Y1663388D01*
X43398Y1663618D01*
X43708Y1663771D01*
X44121Y1663886D01*
X44586Y1663924D01*
X45051Y1663886D01*
X45464Y1663771D01*
X45774Y1663618D01*
X46033Y1663388D01*
X46136Y1663081D01*
G01X47420Y1825921D02*
X44320D01*
X44940Y1826381D01*
G01X47420D02*
Y1825461D01*
G01X53594Y27059D02*
X53364Y27369D01*
X53096Y27524D01*
X52789Y27576D01*
X52406Y27473D01*
X52138Y27214D01*
X52061Y26904D01*
X52099Y26594D01*
X52253Y26336D01*
X53019Y25819D01*
X53364Y25458D01*
X53594Y24941D01*
X53671Y24476D01*
X52061D01*
G01X57966Y34976D02*
Y38076D01*
X58426Y37456D01*
G01Y34976D02*
X57506D01*
G01X52512Y204643D02*
X52435Y205315D01*
X52320Y205883D01*
X52167Y206400D01*
X51975Y206968D01*
X51668Y207743D01*
X53202D01*
G01X57435Y215043D02*
X57167Y215095D01*
X56860Y215250D01*
X56668Y215508D01*
X56592Y215870D01*
X56668Y216231D01*
X56898Y216541D01*
X57243Y216696D01*
X57627D01*
X57857Y216800D01*
X58048Y217058D01*
X58125Y217420D01*
X58010Y217781D01*
X57742Y218040D01*
X57435Y218143D01*
X57128Y218040D01*
X56860Y217781D01*
X56745Y217420D01*
X56822Y217058D01*
X57013Y216800D01*
X57243Y216696D01*
X57627D01*
X57972Y216541D01*
X58202Y216231D01*
X58278Y215870D01*
X58202Y215508D01*
X58010Y215250D01*
X57703Y215095D01*
X57435Y215043D01*
G01X57177Y242123D02*
Y245223D01*
X57637Y244603D01*
G01Y242123D02*
X56717D01*
G01X52805Y234206D02*
X52575Y234516D01*
X52307Y234671D01*
X52000Y234723D01*
X51617Y234620D01*
X51349Y234361D01*
X51272Y234051D01*
X51310Y233741D01*
X51464Y233483D01*
X52230Y232966D01*
X52575Y232605D01*
X52805Y232088D01*
X52882Y231623D01*
X51272D01*
G01X52512Y413501D02*
X52435Y414173D01*
X52320Y414741D01*
X52167Y415258D01*
X51975Y415826D01*
X51668Y416601D01*
X53202D01*
G01X57435Y423901D02*
X57167Y423953D01*
X56860Y424108D01*
X56668Y424366D01*
X56592Y424728D01*
X56668Y425089D01*
X56898Y425399D01*
X57243Y425554D01*
X57627D01*
X57857Y425658D01*
X58048Y425916D01*
X58125Y426278D01*
X58010Y426639D01*
X57742Y426898D01*
X57435Y427001D01*
X57128Y426898D01*
X56860Y426639D01*
X56745Y426278D01*
X56822Y425916D01*
X57013Y425658D01*
X57243Y425554D01*
X57627D01*
X57972Y425399D01*
X58202Y425089D01*
X58278Y424728D01*
X58202Y424366D01*
X58010Y424108D01*
X57703Y423953D01*
X57435Y423901D01*
G01X54447Y509160D02*
X54217Y509470D01*
X53949Y509625D01*
X53642Y509677D01*
X53259Y509574D01*
X52991Y509315D01*
X52914Y509005D01*
X52952Y508695D01*
X53106Y508437D01*
X53872Y507920D01*
X54217Y507559D01*
X54447Y507042D01*
X54524Y506577D01*
X52914D01*
G01X58119Y516727D02*
Y519827D01*
X58579Y519207D01*
G01Y516727D02*
X57659D01*
G01X53972Y1611259D02*
X53895Y1611931D01*
X53780Y1612499D01*
X53627Y1613016D01*
X53435Y1613584D01*
X53128Y1614359D01*
X54662D01*
G01X58845Y1621359D02*
X58577Y1621411D01*
X58270Y1621566D01*
X58078Y1621824D01*
X58002Y1622186D01*
X58078Y1622547D01*
X58308Y1622857D01*
X58653Y1623012D01*
X59037D01*
X59267Y1623116D01*
X59458Y1623374D01*
X59535Y1623736D01*
X59420Y1624097D01*
X59152Y1624356D01*
X58845Y1624459D01*
X58538Y1624356D01*
X58270Y1624097D01*
X58155Y1623736D01*
X58232Y1623374D01*
X58423Y1623116D01*
X58653Y1623012D01*
X59037D01*
X59382Y1622857D01*
X59612Y1622547D01*
X59688Y1622186D01*
X59612Y1621824D01*
X59420Y1621566D01*
X59113Y1621411D01*
X58845Y1621359D01*
G01X52512Y1944958D02*
X52435Y1945630D01*
X52320Y1946198D01*
X52167Y1946715D01*
X51975Y1947283D01*
X51668Y1948058D01*
X53202D01*
G01X57435Y1955358D02*
X57167Y1955410D01*
X56860Y1955565D01*
X56668Y1955823D01*
X56592Y1956185D01*
X56668Y1956546D01*
X56898Y1956856D01*
X57243Y1957011D01*
X57627D01*
X57857Y1957115D01*
X58048Y1957373D01*
X58125Y1957735D01*
X58010Y1958096D01*
X57742Y1958355D01*
X57435Y1958458D01*
X57128Y1958355D01*
X56860Y1958096D01*
X56745Y1957735D01*
X56822Y1957373D01*
X57013Y1957115D01*
X57243Y1957011D01*
X57627D01*
X57972Y1956856D01*
X58202Y1956546D01*
X58278Y1956185D01*
X58202Y1955823D01*
X58010Y1955565D01*
X57703Y1955410D01*
X57435Y1955358D01*
G01X52512Y2049328D02*
X52435Y2050000D01*
X52320Y2050568D01*
X52167Y2051085D01*
X51975Y2051653D01*
X51668Y2052428D01*
X53202D01*
G01X57435Y2059728D02*
X57167Y2059780D01*
X56860Y2059935D01*
X56668Y2060193D01*
X56592Y2060555D01*
X56668Y2060916D01*
X56898Y2061226D01*
X57243Y2061381D01*
X57627D01*
X57857Y2061485D01*
X58048Y2061743D01*
X58125Y2062105D01*
X58010Y2062466D01*
X57742Y2062725D01*
X57435Y2062828D01*
X57128Y2062725D01*
X56860Y2062466D01*
X56745Y2062105D01*
X56822Y2061743D01*
X57013Y2061485D01*
X57243Y2061381D01*
X57627D01*
X57972Y2061226D01*
X58202Y2060916D01*
X58278Y2060555D01*
X58202Y2060193D01*
X58010Y2059935D01*
X57703Y2059780D01*
X57435Y2059728D01*
G01X118621Y1122D02*
X418149D01*
G01X118621Y53288D02*
Y1122D01*
G01X115436Y14010D02*
X115206Y13648D01*
X114900Y13442D01*
X114555Y13390D01*
X114248Y13442D01*
X113941Y13700D01*
X113750Y14010D01*
X113711Y14320D01*
X113788Y14682D01*
X114056Y14940D01*
X114325Y15043D01*
X114670D01*
G01X114325D02*
X114095Y15198D01*
X113903Y15457D01*
X113826Y15767D01*
X113903Y16077D01*
X114095Y16335D01*
X114440Y16490D01*
X114785Y16438D01*
X115130Y16232D01*
G01X112221Y15973D02*
X111991Y16283D01*
X111723Y16438D01*
X111416Y16490D01*
X111033Y16387D01*
X110765Y16128D01*
X110688Y15818D01*
X110726Y15508D01*
X110880Y15250D01*
X111646Y14733D01*
X111991Y14372D01*
X112221Y13855D01*
X112298Y13390D01*
X110688D01*
G01X418149Y53288D02*
X118621D01*
G01Y176122D02*
X418149D01*
G01X118621Y228288D02*
Y176122D01*
G01X418149Y228288D02*
X118621D01*
G01X114658Y330269D02*
Y333369D01*
X115118Y332749D01*
G01Y330269D02*
X114198D01*
G01X115271Y364571D02*
X115041Y364209D01*
X114735Y364003D01*
X114390Y363951D01*
X114083Y364003D01*
X113776Y364261D01*
X113585Y364571D01*
X113546Y364881D01*
X113623Y365243D01*
X113891Y365501D01*
X114160Y365604D01*
X114505D01*
G01X114160D02*
X113930Y365759D01*
X113738Y366018D01*
X113661Y366328D01*
X113738Y366638D01*
X113930Y366896D01*
X114275Y367051D01*
X114620Y366999D01*
X114965Y366793D01*
G01X112056Y366534D02*
X111826Y366844D01*
X111558Y366999D01*
X111251Y367051D01*
X110868Y366948D01*
X110600Y366689D01*
X110523Y366379D01*
X110561Y366069D01*
X110715Y365811D01*
X111481Y365294D01*
X111826Y364933D01*
X112056Y364416D01*
X112133Y363951D01*
X110523D01*
G01X118621Y351122D02*
X418149D01*
G01X118621Y403288D02*
Y351122D01*
G01X418149Y403288D02*
X118621D01*
G01X118622Y526122D02*
X418150D01*
G01X118622Y578288D02*
Y526122D01*
G01X418150Y578288D02*
X118622D01*
G01X112393Y677110D02*
Y680210D01*
X112853Y679590D01*
G01Y677110D02*
X111933D01*
G01X116733Y709150D02*
X116503Y708788D01*
X116197Y708582D01*
X115852Y708530D01*
X115545Y708582D01*
X115238Y708840D01*
X115047Y709150D01*
X115008Y709460D01*
X115085Y709822D01*
X115353Y710080D01*
X115622Y710183D01*
X115967D01*
G01X115622D02*
X115392Y710338D01*
X115200Y710597D01*
X115123Y710907D01*
X115200Y711217D01*
X115392Y711475D01*
X115737Y711630D01*
X116082Y711578D01*
X116427Y711372D01*
G01X113518Y711113D02*
X113288Y711423D01*
X113020Y711578D01*
X112713Y711630D01*
X112330Y711527D01*
X112062Y711268D01*
X111985Y710958D01*
X112023Y710648D01*
X112177Y710390D01*
X112943Y709873D01*
X113288Y709512D01*
X113518Y708995D01*
X113595Y708530D01*
X111985D01*
G01X118622Y701122D02*
X418150D01*
G01X118622Y753288D02*
Y701122D01*
G01X418150Y753288D02*
X118622D01*
G01X118621Y876122D02*
X418149D01*
G01X118621Y928288D02*
Y876122D01*
G01X418149Y928288D02*
X118621D01*
G01X112118Y1026513D02*
Y1029613D01*
X112578Y1028993D01*
G01Y1026513D02*
X111658D01*
G01X116505Y1057316D02*
X116275Y1056954D01*
X115969Y1056748D01*
X115624Y1056696D01*
X115317Y1056748D01*
X115010Y1057006D01*
X114819Y1057316D01*
X114780Y1057626D01*
X114857Y1057988D01*
X115125Y1058246D01*
X115394Y1058349D01*
X115739D01*
G01X115394D02*
X115164Y1058504D01*
X114972Y1058763D01*
X114895Y1059073D01*
X114972Y1059383D01*
X115164Y1059641D01*
X115509Y1059796D01*
X115854Y1059744D01*
X116199Y1059538D01*
G01X113290Y1059279D02*
X113060Y1059589D01*
X112792Y1059744D01*
X112485Y1059796D01*
X112102Y1059693D01*
X111834Y1059434D01*
X111757Y1059124D01*
X111795Y1058814D01*
X111949Y1058556D01*
X112715Y1058039D01*
X113060Y1057678D01*
X113290Y1057161D01*
X113367Y1056696D01*
X111757D01*
G01X118621Y1051122D02*
X418149D01*
G01X118621Y1103288D02*
Y1051122D01*
G01X418149Y1103288D02*
X118621D01*
G01Y1226122D02*
X418149D01*
G01X118621Y1278288D02*
Y1226122D01*
G01X418149Y1278288D02*
X118621D01*
G01X112021Y1374410D02*
Y1377510D01*
X112481Y1376890D01*
G01Y1374410D02*
X111561D01*
G01X115178Y1409118D02*
X114948Y1408756D01*
X114642Y1408550D01*
X114297Y1408498D01*
X113990Y1408550D01*
X113683Y1408808D01*
X113492Y1409118D01*
X113453Y1409428D01*
X113530Y1409790D01*
X113798Y1410048D01*
X114067Y1410151D01*
X114412D01*
G01X114067D02*
X113837Y1410306D01*
X113645Y1410565D01*
X113568Y1410875D01*
X113645Y1411185D01*
X113837Y1411443D01*
X114182Y1411598D01*
X114527Y1411546D01*
X114872Y1411340D01*
G01X111963Y1411081D02*
X111733Y1411391D01*
X111465Y1411546D01*
X111158Y1411598D01*
X110775Y1411495D01*
X110507Y1411236D01*
X110430Y1410926D01*
X110468Y1410616D01*
X110622Y1410358D01*
X111388Y1409841D01*
X111733Y1409480D01*
X111963Y1408963D01*
X112040Y1408498D01*
X110430D01*
G01X118621Y1401122D02*
X418149D01*
G01X118621Y1453288D02*
Y1401122D01*
G01X418149Y1453288D02*
X118621D01*
G01Y1576122D02*
X418149D01*
G01X118621Y1628288D02*
Y1576122D01*
G01X418149Y1628288D02*
X118621D01*
G01X114718Y1723530D02*
Y1726630D01*
X115178Y1726010D01*
G01Y1723530D02*
X114258D01*
G01X114256Y1755419D02*
X114026Y1755057D01*
X113720Y1754851D01*
X113375Y1754799D01*
X113068Y1754851D01*
X112761Y1755109D01*
X112570Y1755419D01*
X112531Y1755729D01*
X112608Y1756091D01*
X112876Y1756349D01*
X113145Y1756452D01*
X113490D01*
G01X113145D02*
X112915Y1756607D01*
X112723Y1756866D01*
X112646Y1757176D01*
X112723Y1757486D01*
X112915Y1757744D01*
X113260Y1757899D01*
X113605Y1757847D01*
X113950Y1757641D01*
G01X111041Y1757382D02*
X110811Y1757692D01*
X110543Y1757847D01*
X110236Y1757899D01*
X109853Y1757796D01*
X109585Y1757537D01*
X109508Y1757227D01*
X109546Y1756917D01*
X109700Y1756659D01*
X110466Y1756142D01*
X110811Y1755781D01*
X111041Y1755264D01*
X111118Y1754799D01*
X109508D01*
G01X118621Y1751122D02*
X418149D01*
G01X118621Y1803288D02*
Y1751122D01*
G01X418149Y1803288D02*
X118621D01*
G01Y1926122D02*
X418149D01*
G01X118621Y1973529D02*
Y1926122D01*
G01X113661Y2072782D02*
Y2075882D01*
X114121Y2075262D01*
G01Y2072782D02*
X113201D01*
G01X143853Y9094D02*
X143623Y8732D01*
X143317Y8526D01*
X142972Y8474D01*
X142665Y8526D01*
X142358Y8784D01*
X142167Y9094D01*
X142128Y9404D01*
X142205Y9766D01*
X142473Y10024D01*
X142742Y10127D01*
X143087D01*
G01X142742D02*
X142512Y10282D01*
X142320Y10541D01*
X142243Y10851D01*
X142320Y11161D01*
X142512Y11419D01*
X142857Y11574D01*
X143202Y11522D01*
X143547Y11316D01*
G01X140753Y9094D02*
X140523Y8732D01*
X140217Y8526D01*
X139872Y8474D01*
X139565Y8526D01*
X139258Y8784D01*
X139067Y9094D01*
X139028Y9404D01*
X139105Y9766D01*
X139373Y10024D01*
X139642Y10127D01*
X139987D01*
G01X139642D02*
X139412Y10282D01*
X139220Y10541D01*
X139143Y10851D01*
X139220Y11161D01*
X139412Y11419D01*
X139757Y11574D01*
X140102Y11522D01*
X140447Y11316D01*
G01X406338Y12933D02*
X130432D01*
Y41477D01*
X406338D01*
Y12933D01*
G01Y187933D02*
X130432D01*
Y216477D01*
X406338D01*
Y187933D01*
G01X142418Y333996D02*
X142150Y334357D01*
X141920Y334564D01*
X141613Y334667D01*
X141345Y334564D01*
X141153Y334357D01*
X141000Y334047D01*
X140962Y333686D01*
X141000Y333376D01*
X141153Y333066D01*
X141383Y332807D01*
X141652Y332704D01*
X141958Y332807D01*
X142227Y333117D01*
X142380Y333582D01*
X142418Y334099D01*
X142342Y334771D01*
X142227Y335132D01*
X142035Y335494D01*
X141767Y335752D01*
X141498Y335804D01*
X141230Y335701D01*
X141038Y335442D01*
G01X138130Y332704D02*
Y335804D01*
X139548Y333582D01*
X137632D01*
G01X146573Y347066D02*
X146343Y346704D01*
X146037Y346498D01*
X145692Y346446D01*
X145385Y346498D01*
X145078Y346756D01*
X144887Y347066D01*
X144848Y347376D01*
X144925Y347738D01*
X145193Y347996D01*
X145462Y348099D01*
X145807D01*
G01X145462D02*
X145232Y348254D01*
X145040Y348513D01*
X144963Y348823D01*
X145040Y349133D01*
X145232Y349391D01*
X145577Y349546D01*
X145922Y349494D01*
X146267Y349288D01*
G01X143473Y347066D02*
X143243Y346704D01*
X142937Y346498D01*
X142592Y346446D01*
X142285Y346498D01*
X141978Y346756D01*
X141787Y347066D01*
X141748Y347376D01*
X141825Y347738D01*
X142093Y347996D01*
X142362Y348099D01*
X142707D01*
G01X142362D02*
X142132Y348254D01*
X141940Y348513D01*
X141863Y348823D01*
X141940Y349133D01*
X142132Y349391D01*
X142477Y349546D01*
X142822Y349494D01*
X143167Y349288D01*
G01X406338Y362933D02*
X130432D01*
Y391477D01*
X406338D01*
Y362933D01*
G01X406339Y537933D02*
X130433D01*
Y566477D01*
X406339D01*
Y537933D01*
G01X142299Y682178D02*
X142031Y682539D01*
X141801Y682746D01*
X141494Y682849D01*
X141226Y682746D01*
X141034Y682539D01*
X140881Y682229D01*
X140843Y681868D01*
X140881Y681558D01*
X141034Y681248D01*
X141264Y680989D01*
X141533Y680886D01*
X141839Y680989D01*
X142108Y681299D01*
X142261Y681764D01*
X142299Y682281D01*
X142223Y682953D01*
X142108Y683314D01*
X141916Y683676D01*
X141648Y683934D01*
X141379Y683986D01*
X141111Y683883D01*
X140919Y683624D01*
G01X138011Y680886D02*
Y683986D01*
X139429Y681764D01*
X137513D01*
G01X143610Y697008D02*
X143380Y696646D01*
X143074Y696440D01*
X142729Y696388D01*
X142422Y696440D01*
X142115Y696698D01*
X141924Y697008D01*
X141885Y697318D01*
X141962Y697680D01*
X142230Y697938D01*
X142499Y698041D01*
X142844D01*
G01X142499D02*
X142269Y698196D01*
X142077Y698455D01*
X142000Y698765D01*
X142077Y699075D01*
X142269Y699333D01*
X142614Y699488D01*
X142959Y699436D01*
X143304Y699230D01*
G01X140510Y697008D02*
X140280Y696646D01*
X139974Y696440D01*
X139629Y696388D01*
X139322Y696440D01*
X139015Y696698D01*
X138824Y697008D01*
X138785Y697318D01*
X138862Y697680D01*
X139130Y697938D01*
X139399Y698041D01*
X139744D01*
G01X139399D02*
X139169Y698196D01*
X138977Y698455D01*
X138900Y698765D01*
X138977Y699075D01*
X139169Y699333D01*
X139514Y699488D01*
X139859Y699436D01*
X140204Y699230D01*
G01X406339Y712933D02*
X130433D01*
Y741477D01*
X406339D01*
Y712933D01*
G01X406338Y887933D02*
X130432D01*
Y916477D01*
X406338D01*
Y887933D01*
G01X142693Y1030776D02*
X142425Y1031137D01*
X142195Y1031344D01*
X141888Y1031447D01*
X141620Y1031344D01*
X141428Y1031137D01*
X141275Y1030827D01*
X141237Y1030466D01*
X141275Y1030156D01*
X141428Y1029846D01*
X141658Y1029587D01*
X141927Y1029484D01*
X142233Y1029587D01*
X142502Y1029897D01*
X142655Y1030362D01*
X142693Y1030879D01*
X142617Y1031551D01*
X142502Y1031912D01*
X142310Y1032274D01*
X142042Y1032532D01*
X141773Y1032584D01*
X141505Y1032481D01*
X141313Y1032222D01*
G01X138405Y1029484D02*
Y1032584D01*
X139823Y1030362D01*
X137907D01*
G01X143115Y1047586D02*
X142885Y1047224D01*
X142579Y1047018D01*
X142234Y1046966D01*
X141927Y1047018D01*
X141620Y1047276D01*
X141429Y1047586D01*
X141390Y1047896D01*
X141467Y1048258D01*
X141735Y1048516D01*
X142004Y1048619D01*
X142349D01*
G01X142004D02*
X141774Y1048774D01*
X141582Y1049033D01*
X141505Y1049343D01*
X141582Y1049653D01*
X141774Y1049911D01*
X142119Y1050066D01*
X142464Y1050014D01*
X142809Y1049808D01*
G01X140015Y1047586D02*
X139785Y1047224D01*
X139479Y1047018D01*
X139134Y1046966D01*
X138827Y1047018D01*
X138520Y1047276D01*
X138329Y1047586D01*
X138290Y1047896D01*
X138367Y1048258D01*
X138635Y1048516D01*
X138904Y1048619D01*
X139249D01*
G01X138904D02*
X138674Y1048774D01*
X138482Y1049033D01*
X138405Y1049343D01*
X138482Y1049653D01*
X138674Y1049911D01*
X139019Y1050066D01*
X139364Y1050014D01*
X139709Y1049808D01*
G01X406338Y1062933D02*
X130432D01*
Y1091477D01*
X406338D01*
Y1062933D01*
G01Y1237933D02*
X130432D01*
Y1266477D01*
X406338D01*
Y1237933D01*
G01X142597Y1378807D02*
X142329Y1379168D01*
X142099Y1379375D01*
X141792Y1379478D01*
X141524Y1379375D01*
X141332Y1379168D01*
X141179Y1378858D01*
X141141Y1378497D01*
X141179Y1378187D01*
X141332Y1377877D01*
X141562Y1377618D01*
X141831Y1377515D01*
X142137Y1377618D01*
X142406Y1377928D01*
X142559Y1378393D01*
X142597Y1378910D01*
X142521Y1379582D01*
X142406Y1379943D01*
X142214Y1380305D01*
X141946Y1380563D01*
X141677Y1380615D01*
X141409Y1380512D01*
X141217Y1380253D01*
G01X138309Y1377515D02*
Y1380615D01*
X139727Y1378393D01*
X137811D01*
G01X141922Y1397243D02*
X141692Y1396881D01*
X141386Y1396675D01*
X141041Y1396623D01*
X140734Y1396675D01*
X140427Y1396933D01*
X140236Y1397243D01*
X140197Y1397553D01*
X140274Y1397915D01*
X140542Y1398173D01*
X140811Y1398276D01*
X141156D01*
G01X140811D02*
X140581Y1398431D01*
X140389Y1398690D01*
X140312Y1399000D01*
X140389Y1399310D01*
X140581Y1399568D01*
X140926Y1399723D01*
X141271Y1399671D01*
X141616Y1399465D01*
G01X138822Y1397243D02*
X138592Y1396881D01*
X138286Y1396675D01*
X137941Y1396623D01*
X137634Y1396675D01*
X137327Y1396933D01*
X137136Y1397243D01*
X137097Y1397553D01*
X137174Y1397915D01*
X137442Y1398173D01*
X137711Y1398276D01*
X138056D01*
G01X137711D02*
X137481Y1398431D01*
X137289Y1398690D01*
X137212Y1399000D01*
X137289Y1399310D01*
X137481Y1399568D01*
X137826Y1399723D01*
X138171Y1399671D01*
X138516Y1399465D01*
G01X406338Y1412933D02*
X130432D01*
Y1441477D01*
X406338D01*
Y1412933D01*
G01Y1587933D02*
X130432D01*
Y1616477D01*
X406338D01*
Y1587933D01*
G01X142746Y1727256D02*
X142478Y1727617D01*
X142248Y1727824D01*
X141941Y1727927D01*
X141673Y1727824D01*
X141481Y1727617D01*
X141328Y1727307D01*
X141290Y1726946D01*
X141328Y1726636D01*
X141481Y1726326D01*
X141711Y1726067D01*
X141980Y1725964D01*
X142286Y1726067D01*
X142555Y1726377D01*
X142708Y1726842D01*
X142746Y1727359D01*
X142670Y1728031D01*
X142555Y1728392D01*
X142363Y1728754D01*
X142095Y1729012D01*
X141826Y1729064D01*
X141558Y1728961D01*
X141366Y1728702D01*
G01X138458Y1725964D02*
Y1729064D01*
X139876Y1726842D01*
X137960D01*
G01X141938Y1747165D02*
X141708Y1746803D01*
X141402Y1746597D01*
X141057Y1746545D01*
X140750Y1746597D01*
X140443Y1746855D01*
X140252Y1747165D01*
X140213Y1747475D01*
X140290Y1747837D01*
X140558Y1748095D01*
X140827Y1748198D01*
X141172D01*
G01X140827D02*
X140597Y1748353D01*
X140405Y1748612D01*
X140328Y1748922D01*
X140405Y1749232D01*
X140597Y1749490D01*
X140942Y1749645D01*
X141287Y1749593D01*
X141632Y1749387D01*
G01X138838Y1747165D02*
X138608Y1746803D01*
X138302Y1746597D01*
X137957Y1746545D01*
X137650Y1746597D01*
X137343Y1746855D01*
X137152Y1747165D01*
X137113Y1747475D01*
X137190Y1747837D01*
X137458Y1748095D01*
X137727Y1748198D01*
X138072D01*
G01X137727D02*
X137497Y1748353D01*
X137305Y1748612D01*
X137228Y1748922D01*
X137305Y1749232D01*
X137497Y1749490D01*
X137842Y1749645D01*
X138187Y1749593D01*
X138532Y1749387D01*
G01X406338Y1762933D02*
X130432D01*
Y1791477D01*
X406338D01*
Y1762933D01*
G01Y1937933D02*
X130432D01*
Y1966477D01*
X406338D01*
Y1937933D01*
G01X418149Y1978288D02*
X124353D01*
G01X142761Y2075436D02*
X142493Y2075797D01*
X142263Y2076004D01*
X141956Y2076107D01*
X141688Y2076004D01*
X141496Y2075797D01*
X141343Y2075487D01*
X141305Y2075126D01*
X141343Y2074816D01*
X141496Y2074506D01*
X141726Y2074247D01*
X141995Y2074144D01*
X142301Y2074247D01*
X142570Y2074557D01*
X142723Y2075022D01*
X142761Y2075539D01*
X142685Y2076211D01*
X142570Y2076572D01*
X142378Y2076934D01*
X142110Y2077192D01*
X141841Y2077244D01*
X141573Y2077141D01*
X141381Y2076882D01*
G01X138473Y2074144D02*
Y2077244D01*
X139891Y2075022D01*
X137975D01*
G01X176074Y7911D02*
Y11011D01*
X175154D01*
X174847Y10856D01*
X174617Y10494D01*
X174540Y10081D01*
X174617Y9668D01*
X174809Y9358D01*
X175154Y9203D01*
X176074D01*
G01X173050Y8531D02*
X172820Y8169D01*
X172514Y7963D01*
X172169Y7911D01*
X171862Y7963D01*
X171555Y8221D01*
X171364Y8531D01*
X171325Y8841D01*
X171402Y9203D01*
X171670Y9461D01*
X171939Y9564D01*
X172284D01*
G01X171939D02*
X171709Y9719D01*
X171517Y9978D01*
X171440Y10288D01*
X171517Y10598D01*
X171709Y10856D01*
X172054Y11011D01*
X172399Y10959D01*
X172744Y10753D01*
G01X169835Y10494D02*
X169605Y10804D01*
X169337Y10959D01*
X169030Y11011D01*
X168647Y10908D01*
X168379Y10649D01*
X168302Y10339D01*
X168340Y10029D01*
X168494Y9771D01*
X169260Y9254D01*
X169605Y8893D01*
X169835Y8376D01*
X169912Y7911D01*
X168302D01*
G01X169940Y42762D02*
Y45862D01*
X169020D01*
X168713Y45707D01*
X168483Y45345D01*
X168406Y44932D01*
X168483Y44519D01*
X168675Y44209D01*
X169020Y44054D01*
X169940D01*
G01X166073Y42762D02*
Y45862D01*
X166533Y45242D01*
G01Y42762D02*
X165613D01*
G01X153079Y55845D02*
X152887Y55535D01*
X152657Y55328D01*
X152389Y55225D01*
X152082Y55328D01*
X151852Y55535D01*
X151622Y55845D01*
X151545Y56258D01*
Y58325D01*
G01X149289Y55225D02*
X149212Y55897D01*
X149097Y56465D01*
X148944Y56982D01*
X148752Y57550D01*
X148445Y58325D01*
X149979D01*
G01X176114Y182703D02*
Y185803D01*
X175194D01*
X174887Y185648D01*
X174657Y185286D01*
X174580Y184873D01*
X174657Y184460D01*
X174849Y184150D01*
X175194Y183995D01*
X176114D01*
G01X173090Y183323D02*
X172860Y182961D01*
X172554Y182755D01*
X172209Y182703D01*
X171902Y182755D01*
X171595Y183013D01*
X171404Y183323D01*
X171365Y183633D01*
X171442Y183995D01*
X171710Y184253D01*
X171979Y184356D01*
X172324D01*
G01X171979D02*
X171749Y184511D01*
X171557Y184770D01*
X171480Y185080D01*
X171557Y185390D01*
X171749Y185648D01*
X172094Y185803D01*
X172439Y185751D01*
X172784Y185545D01*
G01X169875Y185286D02*
X169645Y185596D01*
X169377Y185751D01*
X169070Y185803D01*
X168687Y185700D01*
X168419Y185441D01*
X168342Y185131D01*
X168380Y184821D01*
X168534Y184563D01*
X169300Y184046D01*
X169645Y183685D01*
X169875Y183168D01*
X169952Y182703D01*
X168342D01*
G01X169577Y218761D02*
Y221861D01*
X168657D01*
X168350Y221706D01*
X168120Y221344D01*
X168043Y220931D01*
X168120Y220518D01*
X168312Y220208D01*
X168657Y220053D01*
X169577D01*
G01X165710Y218761D02*
Y221861D01*
X166170Y221241D01*
G01Y218761D02*
X165250D01*
G01X153652Y231075D02*
X153460Y230765D01*
X153230Y230558D01*
X152962Y230455D01*
X152655Y230558D01*
X152425Y230765D01*
X152195Y231075D01*
X152118Y231488D01*
Y233555D01*
G01X149785Y230455D02*
X149517Y230507D01*
X149210Y230662D01*
X149018Y230920D01*
X148942Y231282D01*
X149018Y231643D01*
X149248Y231953D01*
X149593Y232108D01*
X149977D01*
X150207Y232212D01*
X150398Y232470D01*
X150475Y232832D01*
X150360Y233193D01*
X150092Y233452D01*
X149785Y233555D01*
X149478Y233452D01*
X149210Y233193D01*
X149095Y232832D01*
X149172Y232470D01*
X149363Y232212D01*
X149593Y232108D01*
X149977D01*
X150322Y231953D01*
X150552Y231643D01*
X150628Y231282D01*
X150552Y230920D01*
X150360Y230662D01*
X150053Y230507D01*
X149785Y230455D01*
G01X175939Y358024D02*
Y361124D01*
X175019D01*
X174712Y360969D01*
X174482Y360607D01*
X174405Y360194D01*
X174482Y359781D01*
X174674Y359471D01*
X175019Y359316D01*
X175939D01*
G01X172915Y358644D02*
X172685Y358282D01*
X172379Y358076D01*
X172034Y358024D01*
X171727Y358076D01*
X171420Y358334D01*
X171229Y358644D01*
X171190Y358954D01*
X171267Y359316D01*
X171535Y359574D01*
X171804Y359677D01*
X172149D01*
G01X171804D02*
X171574Y359832D01*
X171382Y360091D01*
X171305Y360401D01*
X171382Y360711D01*
X171574Y360969D01*
X171919Y361124D01*
X172264Y361072D01*
X172609Y360866D01*
G01X169700Y360607D02*
X169470Y360917D01*
X169202Y361072D01*
X168895Y361124D01*
X168512Y361021D01*
X168244Y360762D01*
X168167Y360452D01*
X168205Y360142D01*
X168359Y359884D01*
X169125Y359367D01*
X169470Y359006D01*
X169700Y358489D01*
X169777Y358024D01*
X168167D01*
G01X170340Y393142D02*
Y396242D01*
X169420D01*
X169113Y396087D01*
X168883Y395725D01*
X168806Y395312D01*
X168883Y394899D01*
X169075Y394589D01*
X169420Y394434D01*
X170340D01*
G01X166473Y393142D02*
Y396242D01*
X166933Y395622D01*
G01Y393142D02*
X166013D01*
G01X153157Y406307D02*
X152965Y405997D01*
X152735Y405790D01*
X152467Y405687D01*
X152160Y405790D01*
X151930Y405997D01*
X151700Y406307D01*
X151623Y406720D01*
Y408787D01*
G01X149942Y406049D02*
X149673Y405790D01*
X149367Y405687D01*
X149060Y405790D01*
X148792Y406100D01*
X148600Y406565D01*
X148523Y407030D01*
Y407599D01*
X148600Y408064D01*
X148792Y408477D01*
X149022Y408684D01*
X149290Y408787D01*
X149597Y408684D01*
X149827Y408477D01*
X149980Y408167D01*
X150057Y407754D01*
X149980Y407392D01*
X149788Y407030D01*
X149558Y406824D01*
X149290Y406772D01*
X148983Y406875D01*
X148753Y407134D01*
X148523Y407599D01*
G01X176382Y533222D02*
Y536322D01*
X175462D01*
X175155Y536167D01*
X174925Y535805D01*
X174848Y535392D01*
X174925Y534979D01*
X175117Y534669D01*
X175462Y534514D01*
X176382D01*
G01X173358Y533842D02*
X173128Y533480D01*
X172822Y533274D01*
X172477Y533222D01*
X172170Y533274D01*
X171863Y533532D01*
X171672Y533842D01*
X171633Y534152D01*
X171710Y534514D01*
X171978Y534772D01*
X172247Y534875D01*
X172592D01*
G01X172247D02*
X172017Y535030D01*
X171825Y535289D01*
X171748Y535599D01*
X171825Y535909D01*
X172017Y536167D01*
X172362Y536322D01*
X172707Y536270D01*
X173052Y536064D01*
G01X170143Y535805D02*
X169913Y536115D01*
X169645Y536270D01*
X169338Y536322D01*
X168955Y536219D01*
X168687Y535960D01*
X168610Y535650D01*
X168648Y535340D01*
X168802Y535082D01*
X169568Y534565D01*
X169913Y534204D01*
X170143Y533687D01*
X170220Y533222D01*
X168610D01*
G01X169845Y568207D02*
Y571307D01*
X168925D01*
X168618Y571152D01*
X168388Y570790D01*
X168311Y570377D01*
X168388Y569964D01*
X168580Y569654D01*
X168925Y569499D01*
X169845D01*
G01X165978Y568207D02*
Y571307D01*
X166438Y570687D01*
G01Y568207D02*
X165518D01*
G01X154534Y581001D02*
X154342Y580691D01*
X154112Y580484D01*
X153844Y580381D01*
X153537Y580484D01*
X153307Y580691D01*
X153077Y581001D01*
X153000Y581414D01*
Y583481D01*
G01X150667Y580381D02*
Y583481D01*
X151127Y582861D01*
G01Y580381D02*
X150207D01*
G01X147567Y583481D02*
X147874Y583378D01*
X148104Y583119D01*
X148257Y582809D01*
X148372Y582396D01*
X148410Y581931D01*
X148372Y581466D01*
X148257Y581053D01*
X148104Y580743D01*
X147874Y580484D01*
X147567Y580381D01*
X147260Y580484D01*
X147030Y580743D01*
X146877Y581053D01*
X146762Y581466D01*
X146724Y581931D01*
X146762Y582396D01*
X146877Y582809D01*
X147030Y583119D01*
X147260Y583378D01*
X147567Y583481D01*
G01X175539Y707599D02*
Y710699D01*
X174619D01*
X174312Y710544D01*
X174082Y710182D01*
X174005Y709769D01*
X174082Y709356D01*
X174274Y709046D01*
X174619Y708891D01*
X175539D01*
G01X172515Y708219D02*
X172285Y707857D01*
X171979Y707651D01*
X171634Y707599D01*
X171327Y707651D01*
X171020Y707909D01*
X170829Y708219D01*
X170790Y708529D01*
X170867Y708891D01*
X171135Y709149D01*
X171404Y709252D01*
X171749D01*
G01X171404D02*
X171174Y709407D01*
X170982Y709666D01*
X170905Y709976D01*
X170982Y710286D01*
X171174Y710544D01*
X171519Y710699D01*
X171864Y710647D01*
X172209Y710441D01*
G01X169300Y710182D02*
X169070Y710492D01*
X168802Y710647D01*
X168495Y710699D01*
X168112Y710596D01*
X167844Y710337D01*
X167767Y710027D01*
X167805Y709717D01*
X167959Y709459D01*
X168725Y708942D01*
X169070Y708581D01*
X169300Y708064D01*
X169377Y707599D01*
X167767D01*
G01X169940Y742717D02*
Y745817D01*
X169020D01*
X168713Y745662D01*
X168483Y745300D01*
X168406Y744887D01*
X168483Y744474D01*
X168675Y744164D01*
X169020Y744009D01*
X169940D01*
G01X166073Y742717D02*
Y745817D01*
X166533Y745197D01*
G01Y742717D02*
X165613D01*
G01X154974Y756363D02*
X154782Y756053D01*
X154552Y755846D01*
X154284Y755743D01*
X153977Y755846D01*
X153747Y756053D01*
X153517Y756363D01*
X153440Y756776D01*
Y758843D01*
G01X151107Y755743D02*
Y758843D01*
X151567Y758223D01*
G01Y755743D02*
X150647D01*
G01X148007D02*
Y758843D01*
X148467Y758223D01*
G01Y755743D02*
X147547D01*
G01X177683Y882789D02*
Y885889D01*
X176763D01*
X176456Y885734D01*
X176226Y885372D01*
X176149Y884959D01*
X176226Y884546D01*
X176418Y884236D01*
X176763Y884081D01*
X177683D01*
G01X174659Y883409D02*
X174429Y883047D01*
X174123Y882841D01*
X173778Y882789D01*
X173471Y882841D01*
X173164Y883099D01*
X172973Y883409D01*
X172934Y883719D01*
X173011Y884081D01*
X173279Y884339D01*
X173548Y884442D01*
X173893D01*
G01X173548D02*
X173318Y884597D01*
X173126Y884856D01*
X173049Y885166D01*
X173126Y885476D01*
X173318Y885734D01*
X173663Y885889D01*
X174008Y885837D01*
X174353Y885631D01*
G01X171444Y885372D02*
X171214Y885682D01*
X170946Y885837D01*
X170639Y885889D01*
X170256Y885786D01*
X169988Y885527D01*
X169911Y885217D01*
X169949Y884907D01*
X170103Y884649D01*
X170869Y884132D01*
X171214Y883771D01*
X171444Y883254D01*
X171521Y882789D01*
X169911D01*
G01X169806Y918176D02*
Y921276D01*
X168886D01*
X168579Y921121D01*
X168349Y920759D01*
X168272Y920346D01*
X168349Y919933D01*
X168541Y919623D01*
X168886Y919468D01*
X169806D01*
G01X165939Y918176D02*
Y921276D01*
X166399Y920656D01*
G01Y918176D02*
X165479D01*
G01X158144Y930972D02*
X157952Y930662D01*
X157722Y930455D01*
X157454Y930352D01*
X157147Y930455D01*
X156917Y930662D01*
X156687Y930972D01*
X156610Y931385D01*
Y933452D01*
G01X154277Y930352D02*
Y933452D01*
X154737Y932832D01*
G01Y930352D02*
X153817D01*
G01X151905Y932935D02*
X151675Y933245D01*
X151407Y933400D01*
X151100Y933452D01*
X150717Y933349D01*
X150449Y933090D01*
X150372Y932780D01*
X150410Y932470D01*
X150564Y932212D01*
X151330Y931695D01*
X151675Y931334D01*
X151905Y930817D01*
X151982Y930352D01*
X150372D01*
G01X176877Y1057444D02*
Y1060544D01*
X175957D01*
X175650Y1060389D01*
X175420Y1060027D01*
X175343Y1059614D01*
X175420Y1059201D01*
X175612Y1058891D01*
X175957Y1058736D01*
X176877D01*
G01X173853Y1058064D02*
X173623Y1057702D01*
X173317Y1057496D01*
X172972Y1057444D01*
X172665Y1057496D01*
X172358Y1057754D01*
X172167Y1058064D01*
X172128Y1058374D01*
X172205Y1058736D01*
X172473Y1058994D01*
X172742Y1059097D01*
X173087D01*
G01X172742D02*
X172512Y1059252D01*
X172320Y1059511D01*
X172243Y1059821D01*
X172320Y1060131D01*
X172512Y1060389D01*
X172857Y1060544D01*
X173202Y1060492D01*
X173547Y1060286D01*
G01X170638Y1060027D02*
X170408Y1060337D01*
X170140Y1060492D01*
X169833Y1060544D01*
X169450Y1060441D01*
X169182Y1060182D01*
X169105Y1059872D01*
X169143Y1059562D01*
X169297Y1059304D01*
X170063Y1058787D01*
X170408Y1058426D01*
X170638Y1057909D01*
X170715Y1057444D01*
X169105D01*
G01X169938Y1093232D02*
Y1096332D01*
X169018D01*
X168711Y1096177D01*
X168481Y1095815D01*
X168404Y1095402D01*
X168481Y1094989D01*
X168673Y1094679D01*
X169018Y1094524D01*
X169938D01*
G01X166071Y1093232D02*
Y1096332D01*
X166531Y1095712D01*
G01Y1093232D02*
X165611D01*
G01X155050Y1107494D02*
X154858Y1107184D01*
X154628Y1106977D01*
X154360Y1106874D01*
X154053Y1106977D01*
X153823Y1107184D01*
X153593Y1107494D01*
X153516Y1107907D01*
Y1109974D01*
G01X151183Y1106874D02*
Y1109974D01*
X151643Y1109354D01*
G01Y1106874D02*
X150723D01*
G01X148926Y1107494D02*
X148696Y1107132D01*
X148390Y1106926D01*
X148045Y1106874D01*
X147738Y1106926D01*
X147431Y1107184D01*
X147240Y1107494D01*
X147201Y1107804D01*
X147278Y1108166D01*
X147546Y1108424D01*
X147815Y1108527D01*
X148160D01*
G01X147815D02*
X147585Y1108682D01*
X147393Y1108941D01*
X147316Y1109251D01*
X147393Y1109561D01*
X147585Y1109819D01*
X147930Y1109974D01*
X148275Y1109922D01*
X148620Y1109716D01*
G01X176477Y1233171D02*
Y1236271D01*
X175557D01*
X175250Y1236116D01*
X175020Y1235754D01*
X174943Y1235341D01*
X175020Y1234928D01*
X175212Y1234618D01*
X175557Y1234463D01*
X176477D01*
G01X173453Y1233791D02*
X173223Y1233429D01*
X172917Y1233223D01*
X172572Y1233171D01*
X172265Y1233223D01*
X171958Y1233481D01*
X171767Y1233791D01*
X171728Y1234101D01*
X171805Y1234463D01*
X172073Y1234721D01*
X172342Y1234824D01*
X172687D01*
G01X172342D02*
X172112Y1234979D01*
X171920Y1235238D01*
X171843Y1235548D01*
X171920Y1235858D01*
X172112Y1236116D01*
X172457Y1236271D01*
X172802Y1236219D01*
X173147Y1236013D01*
G01X170238Y1235754D02*
X170008Y1236064D01*
X169740Y1236219D01*
X169433Y1236271D01*
X169050Y1236168D01*
X168782Y1235909D01*
X168705Y1235599D01*
X168743Y1235289D01*
X168897Y1235031D01*
X169663Y1234514D01*
X170008Y1234153D01*
X170238Y1233636D01*
X170315Y1233171D01*
X168705D01*
G01X169269Y1268691D02*
Y1271791D01*
X168349D01*
X168042Y1271636D01*
X167812Y1271274D01*
X167735Y1270861D01*
X167812Y1270448D01*
X168004Y1270138D01*
X168349Y1269983D01*
X169269D01*
G01X165402Y1268691D02*
Y1271791D01*
X165862Y1271171D01*
G01Y1268691D02*
X164942D01*
G01X156427Y1281516D02*
X156235Y1281206D01*
X156005Y1280999D01*
X155737Y1280896D01*
X155430Y1280999D01*
X155200Y1281206D01*
X154970Y1281516D01*
X154893Y1281929D01*
Y1283996D01*
G01X152560Y1280896D02*
Y1283996D01*
X153020Y1283376D01*
G01Y1280896D02*
X152100D01*
G01X149000D02*
Y1283996D01*
X150418Y1281774D01*
X148502D01*
G01X176381Y1407839D02*
Y1410939D01*
X175461D01*
X175154Y1410784D01*
X174924Y1410422D01*
X174847Y1410009D01*
X174924Y1409596D01*
X175116Y1409286D01*
X175461Y1409131D01*
X176381D01*
G01X173357Y1408459D02*
X173127Y1408097D01*
X172821Y1407891D01*
X172476Y1407839D01*
X172169Y1407891D01*
X171862Y1408149D01*
X171671Y1408459D01*
X171632Y1408769D01*
X171709Y1409131D01*
X171977Y1409389D01*
X172246Y1409492D01*
X172591D01*
G01X172246D02*
X172016Y1409647D01*
X171824Y1409906D01*
X171747Y1410216D01*
X171824Y1410526D01*
X172016Y1410784D01*
X172361Y1410939D01*
X172706Y1410887D01*
X173051Y1410681D01*
G01X170142Y1410422D02*
X169912Y1410732D01*
X169644Y1410887D01*
X169337Y1410939D01*
X168954Y1410836D01*
X168686Y1410577D01*
X168609Y1410267D01*
X168647Y1409957D01*
X168801Y1409699D01*
X169567Y1409182D01*
X169912Y1408821D01*
X170142Y1408304D01*
X170219Y1407839D01*
X168609D01*
G01X169979Y1442689D02*
Y1445789D01*
X169059D01*
X168752Y1445634D01*
X168522Y1445272D01*
X168445Y1444859D01*
X168522Y1444446D01*
X168714Y1444136D01*
X169059Y1443981D01*
X169979D01*
G01X166112Y1442689D02*
Y1445789D01*
X166572Y1445169D01*
G01Y1442689D02*
X165652D01*
G01X155530Y1457419D02*
X155338Y1457109D01*
X155108Y1456902D01*
X154840Y1456799D01*
X154533Y1456902D01*
X154303Y1457109D01*
X154073Y1457419D01*
X153996Y1457832D01*
Y1459899D01*
G01X151663Y1456799D02*
Y1459899D01*
X152123Y1459279D01*
G01Y1456799D02*
X151203D01*
G01X149406Y1457264D02*
X149176Y1457006D01*
X148908Y1456851D01*
X148563Y1456799D01*
X148218Y1456902D01*
X147950Y1457109D01*
X147758Y1457471D01*
X147720Y1457884D01*
X147796Y1458297D01*
X147988Y1458556D01*
X148256Y1458762D01*
X148525Y1458814D01*
X148793Y1458762D01*
X149138Y1458556D01*
X149023Y1459899D01*
X147988D01*
G01X177588Y1583031D02*
Y1586131D01*
X176668D01*
X176361Y1585976D01*
X176131Y1585614D01*
X176054Y1585201D01*
X176131Y1584788D01*
X176323Y1584478D01*
X176668Y1584323D01*
X177588D01*
G01X174564Y1583651D02*
X174334Y1583289D01*
X174028Y1583083D01*
X173683Y1583031D01*
X173376Y1583083D01*
X173069Y1583341D01*
X172878Y1583651D01*
X172839Y1583961D01*
X172916Y1584323D01*
X173184Y1584581D01*
X173453Y1584684D01*
X173798D01*
G01X173453D02*
X173223Y1584839D01*
X173031Y1585098D01*
X172954Y1585408D01*
X173031Y1585718D01*
X173223Y1585976D01*
X173568Y1586131D01*
X173913Y1586079D01*
X174258Y1585873D01*
G01X171349Y1585614D02*
X171119Y1585924D01*
X170851Y1586079D01*
X170544Y1586131D01*
X170161Y1586028D01*
X169893Y1585769D01*
X169816Y1585459D01*
X169854Y1585149D01*
X170008Y1584891D01*
X170774Y1584374D01*
X171119Y1584013D01*
X171349Y1583496D01*
X171426Y1583031D01*
X169816D01*
G01X170380Y1617747D02*
Y1620847D01*
X169460D01*
X169153Y1620692D01*
X168923Y1620330D01*
X168846Y1619917D01*
X168923Y1619504D01*
X169115Y1619194D01*
X169460Y1619039D01*
X170380D01*
G01X166513Y1617747D02*
Y1620847D01*
X166973Y1620227D01*
G01Y1617747D02*
X166053D01*
G01X155968Y1631441D02*
X155776Y1631131D01*
X155546Y1630924D01*
X155278Y1630821D01*
X154971Y1630924D01*
X154741Y1631131D01*
X154511Y1631441D01*
X154434Y1631854D01*
Y1633921D01*
G01X152101Y1630821D02*
Y1633921D01*
X152561Y1633301D01*
G01Y1630821D02*
X151641D01*
G01X149729Y1632113D02*
X149461Y1632474D01*
X149231Y1632681D01*
X148924Y1632784D01*
X148656Y1632681D01*
X148464Y1632474D01*
X148311Y1632164D01*
X148273Y1631803D01*
X148311Y1631493D01*
X148464Y1631183D01*
X148694Y1630924D01*
X148963Y1630821D01*
X149269Y1630924D01*
X149538Y1631234D01*
X149691Y1631699D01*
X149729Y1632216D01*
X149653Y1632888D01*
X149538Y1633249D01*
X149346Y1633611D01*
X149078Y1633869D01*
X148809Y1633921D01*
X148541Y1633818D01*
X148349Y1633559D01*
G01X169711Y1793072D02*
Y1796172D01*
X168791D01*
X168484Y1796017D01*
X168254Y1795655D01*
X168177Y1795242D01*
X168254Y1794829D01*
X168446Y1794519D01*
X168791Y1794364D01*
X169711D01*
G01X165844Y1793072D02*
Y1796172D01*
X166304Y1795552D01*
G01Y1793072D02*
X165384D01*
G01X175846Y1932610D02*
Y1935710D01*
X174926D01*
X174619Y1935555D01*
X174389Y1935193D01*
X174312Y1934780D01*
X174389Y1934367D01*
X174581Y1934057D01*
X174926Y1933902D01*
X175846D01*
G01X172822Y1933230D02*
X172592Y1932868D01*
X172286Y1932662D01*
X171941Y1932610D01*
X171634Y1932662D01*
X171327Y1932920D01*
X171136Y1933230D01*
X171097Y1933540D01*
X171174Y1933902D01*
X171442Y1934160D01*
X171711Y1934263D01*
X172056D01*
G01X171711D02*
X171481Y1934418D01*
X171289Y1934677D01*
X171212Y1934987D01*
X171289Y1935297D01*
X171481Y1935555D01*
X171826Y1935710D01*
X172171Y1935658D01*
X172516Y1935452D01*
G01X169607Y1935193D02*
X169377Y1935503D01*
X169109Y1935658D01*
X168802Y1935710D01*
X168419Y1935607D01*
X168151Y1935348D01*
X168074Y1935038D01*
X168112Y1934728D01*
X168266Y1934470D01*
X169032Y1933953D01*
X169377Y1933592D01*
X169607Y1933075D01*
X169684Y1932610D01*
X168074D01*
G01X169711Y1967997D02*
Y1971097D01*
X168791D01*
X168484Y1970942D01*
X168254Y1970580D01*
X168177Y1970167D01*
X168254Y1969754D01*
X168446Y1969444D01*
X168791Y1969289D01*
X169711D01*
G01X165844Y1967997D02*
Y1971097D01*
X166304Y1970477D01*
G01Y1967997D02*
X165384D01*
G01X162213Y1983107D02*
X162021Y1982797D01*
X161791Y1982590D01*
X161523Y1982487D01*
X161216Y1982590D01*
X160986Y1982797D01*
X160756Y1983107D01*
X160679Y1983520D01*
Y1985587D01*
G01X158346Y1982487D02*
Y1985587D01*
X158806Y1984967D01*
G01Y1982487D02*
X157886D01*
G01X155246D02*
X154978Y1982539D01*
X154671Y1982694D01*
X154479Y1982952D01*
X154403Y1983314D01*
X154479Y1983675D01*
X154709Y1983985D01*
X155054Y1984140D01*
X155438D01*
X155668Y1984244D01*
X155859Y1984502D01*
X155936Y1984864D01*
X155821Y1985225D01*
X155553Y1985484D01*
X155246Y1985587D01*
X154939Y1985484D01*
X154671Y1985225D01*
X154556Y1984864D01*
X154633Y1984502D01*
X154824Y1984244D01*
X155054Y1984140D01*
X155438D01*
X155783Y1983985D01*
X156013Y1983675D01*
X156089Y1983314D01*
X156013Y1982952D01*
X155821Y1982694D01*
X155514Y1982539D01*
X155246Y1982487D01*
G01X178258Y1757953D02*
Y1761053D01*
X177338D01*
X177031Y1760898D01*
X176801Y1760536D01*
X176724Y1760123D01*
X176801Y1759710D01*
X176993Y1759400D01*
X177338Y1759245D01*
X178258D01*
G01X175234Y1758573D02*
X175004Y1758211D01*
X174698Y1758005D01*
X174353Y1757953D01*
X174046Y1758005D01*
X173739Y1758263D01*
X173548Y1758573D01*
X173509Y1758883D01*
X173586Y1759245D01*
X173854Y1759503D01*
X174123Y1759606D01*
X174468D01*
G01X174123D02*
X173893Y1759761D01*
X173701Y1760020D01*
X173624Y1760330D01*
X173701Y1760640D01*
X173893Y1760898D01*
X174238Y1761053D01*
X174583Y1761001D01*
X174928Y1760795D01*
G01X172019Y1760536D02*
X171789Y1760846D01*
X171521Y1761001D01*
X171214Y1761053D01*
X170831Y1760950D01*
X170563Y1760691D01*
X170486Y1760381D01*
X170524Y1760071D01*
X170678Y1759813D01*
X171444Y1759296D01*
X171789Y1758935D01*
X172019Y1758418D01*
X172096Y1757953D01*
X170486D01*
G01X178214Y1806717D02*
X178022Y1806407D01*
X177792Y1806200D01*
X177524Y1806097D01*
X177217Y1806200D01*
X176987Y1806407D01*
X176757Y1806717D01*
X176680Y1807130D01*
Y1809197D01*
G01X174347Y1806097D02*
Y1809197D01*
X174807Y1808577D01*
G01Y1806097D02*
X173887D01*
G01X171324D02*
X171247Y1806769D01*
X171132Y1807337D01*
X170979Y1807854D01*
X170787Y1808422D01*
X170480Y1809197D01*
X172014D01*
G01X213400Y-103934D02*
X214200Y-104600D01*
X215100Y-105000D01*
X215900D01*
X216700Y-104600D01*
X217300Y-103934D01*
X217600Y-103000D01*
X217400Y-102067D01*
X216900Y-101267D01*
X216000Y-100733D01*
X214800Y-100467D01*
X214100Y-99933D01*
X213800Y-99000D01*
X214000Y-98067D01*
X214500Y-97400D01*
X215200Y-97000D01*
X215900D01*
X216600Y-97267D01*
X217200Y-97933D01*
G01X222300Y-97000D02*
X224700D01*
G01X223500D02*
Y-105000D01*
G01X222300D02*
X224700D01*
G01X229500Y-97000D02*
Y-105000D01*
X233500D01*
G01X237300D02*
Y-97000D01*
G01X241100D02*
X237300Y-101934D01*
G01X241700Y-105000D02*
X239000Y-99667D01*
G01X246200Y-102333D02*
X248800D01*
G01X256300Y-100733D02*
X256700Y-100333D01*
X257000Y-99667D01*
X257200Y-98733D01*
X257000Y-97933D01*
X256600Y-97400D01*
X255900Y-97000D01*
X253200D01*
Y-105000D01*
X256500D01*
X257200Y-104467D01*
X257600Y-103667D01*
X257800Y-102733D01*
X257600Y-101800D01*
X257000Y-101000D01*
X256300Y-100733D01*
X253200D01*
G01X263500Y-105000D02*
X262700Y-104867D01*
X262000Y-104333D01*
X261400Y-103533D01*
X261000Y-102600D01*
X260800Y-101533D01*
Y-100467D01*
X261000Y-99400D01*
X261400Y-98467D01*
X262000Y-97667D01*
X262700Y-97133D01*
X263500Y-97000D01*
X264300Y-97133D01*
X265000Y-97667D01*
X265600Y-98467D01*
X266000Y-99400D01*
X266200Y-100467D01*
Y-101533D01*
X266000Y-102600D01*
X265600Y-103533D01*
X265000Y-104333D01*
X264300Y-104867D01*
X263500Y-105000D01*
G01X271500Y-97000D02*
Y-105000D01*
G01X269200Y-97000D02*
X273800D01*
G01X202000Y-72000D02*
Y-80000D01*
X206000D01*
G01X213800D02*
Y-74667D01*
G01Y-75600D02*
X213400Y-75067D01*
X212800Y-74800D01*
X212100Y-74667D01*
X211400Y-74933D01*
X210800Y-75467D01*
X210400Y-76267D01*
X210200Y-77333D01*
X210400Y-78400D01*
X210800Y-79200D01*
X211400Y-79733D01*
X212100Y-80000D01*
X212800Y-79867D01*
X213400Y-79467D01*
X213800Y-78934D01*
G01X217900Y-82400D02*
X218500Y-82667D01*
X219300Y-82400D01*
X219800Y-81867D01*
X220200Y-81200D01*
X220800Y-79067D01*
X222100Y-74667D01*
G01X218900D02*
X220800Y-79067D01*
G01X226500Y-76400D02*
X229700D01*
X229400Y-75467D01*
X228900Y-74933D01*
X228200Y-74667D01*
X227500Y-74800D01*
X226900Y-75200D01*
X226500Y-76133D01*
X226300Y-76934D01*
Y-77733D01*
X226500Y-78533D01*
X227000Y-79333D01*
X227600Y-79867D01*
X228300Y-80000D01*
X229000Y-79733D01*
X229700Y-78934D01*
G01X234600Y-80000D02*
Y-74667D01*
G01Y-75733D02*
X235100Y-75200D01*
X235600Y-74800D01*
X236300Y-74667D01*
X236800Y-74800D01*
X237400Y-75200D01*
G01X240933Y879577D02*
Y882677D01*
X240013D01*
X239706Y882522D01*
X239476Y882160D01*
X239399Y881747D01*
X239476Y881334D01*
X239668Y881024D01*
X240013Y880869D01*
X240933D01*
G01X237833Y879577D02*
Y882677D01*
X236874D01*
X236568Y882522D01*
X236376Y882315D01*
X236299Y881902D01*
X236376Y881489D01*
X236606Y881230D01*
X236874Y881075D01*
X237833D01*
G01X236874D02*
X236299Y879577D01*
G01X233199D02*
X234733D01*
Y882677D01*
X233199D01*
G01X233813Y881179D02*
X234733D01*
G01X231671Y879990D02*
X231364Y879732D01*
X231019Y879577D01*
X230713D01*
X230406Y879732D01*
X230176Y879990D01*
X230061Y880352D01*
X230138Y880714D01*
X230329Y881024D01*
X230674Y881230D01*
X231134Y881334D01*
X231403Y881540D01*
X231518Y881902D01*
X231441Y882264D01*
X231249Y882522D01*
X230981Y882677D01*
X230713D01*
X230444Y882574D01*
X230214Y882315D01*
G01X228571Y879990D02*
X228264Y879732D01*
X227919Y879577D01*
X227613D01*
X227306Y879732D01*
X227076Y879990D01*
X226961Y880352D01*
X227038Y880714D01*
X227229Y881024D01*
X227574Y881230D01*
X228034Y881334D01*
X228303Y881540D01*
X228418Y881902D01*
X228341Y882264D01*
X228149Y882522D01*
X227881Y882677D01*
X227613D01*
X227344Y882574D01*
X227114Y882315D01*
G01X225164Y880610D02*
X224168D01*
G01X222294Y879577D02*
Y882677D01*
X220838D01*
G01X221374Y881179D02*
X222294D01*
G01X218926Y882677D02*
X218006D01*
G01X218466D02*
Y879577D01*
G01X218926D02*
X218006D01*
G01X215366Y882677D02*
Y879577D01*
G01X216248Y882677D02*
X214484D01*
G01X223400Y-128934D02*
X224200Y-129600D01*
X225100Y-130000D01*
X225900D01*
X226700Y-129600D01*
X227300Y-128934D01*
X227600Y-128000D01*
X227400Y-127067D01*
X226900Y-126267D01*
X226000Y-125733D01*
X224800Y-125467D01*
X224100Y-124933D01*
X223800Y-124000D01*
X224000Y-123067D01*
X224500Y-122400D01*
X225200Y-122000D01*
X225900D01*
X226600Y-122267D01*
X227200Y-122933D01*
G01X235300Y-130000D02*
Y-124667D01*
G01Y-125600D02*
X234900Y-125067D01*
X234300Y-124800D01*
X233600Y-124667D01*
X232900Y-124933D01*
X232300Y-125467D01*
X231900Y-126267D01*
X231700Y-127333D01*
X231900Y-128400D01*
X232300Y-129200D01*
X232900Y-129733D01*
X233600Y-130000D01*
X234300Y-129867D01*
X234900Y-129467D01*
X235300Y-128934D01*
G01X239800Y-130000D02*
Y-124667D01*
G01Y-126000D02*
X240200Y-125333D01*
X240800Y-124800D01*
X241600Y-124667D01*
X242300Y-124800D01*
X242900Y-125333D01*
X243200Y-126267D01*
Y-130000D01*
G01X251300Y-122000D02*
Y-130000D01*
G01Y-128800D02*
X250900Y-129467D01*
X250300Y-129867D01*
X249600Y-130000D01*
X248800Y-129733D01*
X248200Y-129067D01*
X247800Y-128267D01*
X247700Y-127333D01*
X247800Y-126400D01*
X248200Y-125600D01*
X248800Y-124933D01*
X249600Y-124667D01*
X250300Y-124800D01*
X250800Y-125067D01*
X251300Y-125600D01*
G01X255400Y-132400D02*
X256000Y-132667D01*
X256800Y-132400D01*
X257300Y-131867D01*
X257700Y-131200D01*
X258300Y-129067D01*
X259600Y-124667D01*
G01X256400D02*
X258300Y-129067D01*
G01X269067Y1052954D02*
Y1056054D01*
X268147D01*
X267840Y1055899D01*
X267610Y1055537D01*
X267533Y1055124D01*
X267610Y1054711D01*
X267802Y1054401D01*
X268147Y1054246D01*
X269067D01*
G01X265967Y1052954D02*
Y1056054D01*
X265008D01*
X264702Y1055899D01*
X264510Y1055692D01*
X264433Y1055279D01*
X264510Y1054866D01*
X264740Y1054607D01*
X265008Y1054452D01*
X265967D01*
G01X265008D02*
X264433Y1052954D01*
G01X261333D02*
X262867D01*
Y1056054D01*
X261333D01*
G01X261947Y1054556D02*
X262867D01*
G01X259805Y1053367D02*
X259498Y1053109D01*
X259153Y1052954D01*
X258847D01*
X258540Y1053109D01*
X258310Y1053367D01*
X258195Y1053729D01*
X258272Y1054091D01*
X258463Y1054401D01*
X258808Y1054607D01*
X259268Y1054711D01*
X259537Y1054917D01*
X259652Y1055279D01*
X259575Y1055641D01*
X259383Y1055899D01*
X259115Y1056054D01*
X258847D01*
X258578Y1055951D01*
X258348Y1055692D01*
G01X256705Y1053367D02*
X256398Y1053109D01*
X256053Y1052954D01*
X255747D01*
X255440Y1053109D01*
X255210Y1053367D01*
X255095Y1053729D01*
X255172Y1054091D01*
X255363Y1054401D01*
X255708Y1054607D01*
X256168Y1054711D01*
X256437Y1054917D01*
X256552Y1055279D01*
X256475Y1055641D01*
X256283Y1055899D01*
X256015Y1056054D01*
X255747D01*
X255478Y1055951D01*
X255248Y1055692D01*
G01X253298Y1053987D02*
X252302D01*
G01X250428Y1052954D02*
Y1056054D01*
X248972D01*
G01X249508Y1054556D02*
X250428D01*
G01X247060Y1056054D02*
X246140D01*
G01X246600D02*
Y1052954D01*
G01X247060D02*
X246140D01*
G01X243500Y1056054D02*
Y1052954D01*
G01X244382Y1056054D02*
X242618D01*
G01X364986Y127165D02*
G03I-57900J0D01*
G01X290652Y177820D02*
Y180920D01*
X289732D01*
X289425Y180765D01*
X289195Y180403D01*
X289118Y179990D01*
X289195Y179577D01*
X289387Y179267D01*
X289732Y179112D01*
X290652D01*
G01X287552Y177820D02*
Y180920D01*
X286593D01*
X286287Y180765D01*
X286095Y180558D01*
X286018Y180145D01*
X286095Y179732D01*
X286325Y179473D01*
X286593Y179318D01*
X287552D01*
G01X286593D02*
X286018Y177820D01*
G01X282918D02*
X284452D01*
Y180920D01*
X282918D01*
G01X283532Y179422D02*
X284452D01*
G01X281390Y178233D02*
X281083Y177975D01*
X280738Y177820D01*
X280432D01*
X280125Y177975D01*
X279895Y178233D01*
X279780Y178595D01*
X279857Y178957D01*
X280048Y179267D01*
X280393Y179473D01*
X280853Y179577D01*
X281122Y179783D01*
X281237Y180145D01*
X281160Y180507D01*
X280968Y180765D01*
X280700Y180920D01*
X280432D01*
X280163Y180817D01*
X279933Y180558D01*
G01X278290Y178233D02*
X277983Y177975D01*
X277638Y177820D01*
X277332D01*
X277025Y177975D01*
X276795Y178233D01*
X276680Y178595D01*
X276757Y178957D01*
X276948Y179267D01*
X277293Y179473D01*
X277753Y179577D01*
X278022Y179783D01*
X278137Y180145D01*
X278060Y180507D01*
X277868Y180765D01*
X277600Y180920D01*
X277332D01*
X277063Y180817D01*
X276833Y180558D01*
G01X274883Y178853D02*
X273887D01*
G01X272013Y177820D02*
Y180920D01*
X270557D01*
G01X271093Y179422D02*
X272013D01*
G01X268645Y180920D02*
X267725D01*
G01X268185D02*
Y177820D01*
G01X268645D02*
X267725D01*
G01X265085Y180920D02*
Y177820D01*
G01X265967Y180920D02*
X264203D01*
G01X290652Y352820D02*
Y355920D01*
X289732D01*
X289425Y355765D01*
X289195Y355403D01*
X289118Y354990D01*
X289195Y354577D01*
X289387Y354267D01*
X289732Y354112D01*
X290652D01*
G01X287552Y352820D02*
Y355920D01*
X286593D01*
X286287Y355765D01*
X286095Y355558D01*
X286018Y355145D01*
X286095Y354732D01*
X286325Y354473D01*
X286593Y354318D01*
X287552D01*
G01X286593D02*
X286018Y352820D01*
G01X282918D02*
X284452D01*
Y355920D01*
X282918D01*
G01X283532Y354422D02*
X284452D01*
G01X281390Y353233D02*
X281083Y352975D01*
X280738Y352820D01*
X280432D01*
X280125Y352975D01*
X279895Y353233D01*
X279780Y353595D01*
X279857Y353957D01*
X280048Y354267D01*
X280393Y354473D01*
X280853Y354577D01*
X281122Y354783D01*
X281237Y355145D01*
X281160Y355507D01*
X280968Y355765D01*
X280700Y355920D01*
X280432D01*
X280163Y355817D01*
X279933Y355558D01*
G01X278290Y353233D02*
X277983Y352975D01*
X277638Y352820D01*
X277332D01*
X277025Y352975D01*
X276795Y353233D01*
X276680Y353595D01*
X276757Y353957D01*
X276948Y354267D01*
X277293Y354473D01*
X277753Y354577D01*
X278022Y354783D01*
X278137Y355145D01*
X278060Y355507D01*
X277868Y355765D01*
X277600Y355920D01*
X277332D01*
X277063Y355817D01*
X276833Y355558D01*
G01X274883Y353853D02*
X273887D01*
G01X272013Y352820D02*
Y355920D01*
X270557D01*
G01X271093Y354422D02*
X272013D01*
G01X268645Y355920D02*
X267725D01*
G01X268185D02*
Y352820D01*
G01X268645D02*
X267725D01*
G01X265085Y355920D02*
Y352820D01*
G01X265967Y355920D02*
X264203D01*
G01X364986Y477165D02*
G03X346707Y434944I-57901J0D01*
G01X290653Y527820D02*
Y530920D01*
X289733D01*
X289426Y530765D01*
X289196Y530403D01*
X289119Y529990D01*
X289196Y529577D01*
X289388Y529267D01*
X289733Y529112D01*
X290653D01*
G01X287553Y527820D02*
Y530920D01*
X286594D01*
X286288Y530765D01*
X286096Y530558D01*
X286019Y530145D01*
X286096Y529732D01*
X286326Y529473D01*
X286594Y529318D01*
X287553D01*
G01X286594D02*
X286019Y527820D01*
G01X282919D02*
X284453D01*
Y530920D01*
X282919D01*
G01X283533Y529422D02*
X284453D01*
G01X281391Y528233D02*
X281084Y527975D01*
X280739Y527820D01*
X280433D01*
X280126Y527975D01*
X279896Y528233D01*
X279781Y528595D01*
X279858Y528957D01*
X280049Y529267D01*
X280394Y529473D01*
X280854Y529577D01*
X281123Y529783D01*
X281238Y530145D01*
X281161Y530507D01*
X280969Y530765D01*
X280701Y530920D01*
X280433D01*
X280164Y530817D01*
X279934Y530558D01*
G01X278291Y528233D02*
X277984Y527975D01*
X277639Y527820D01*
X277333D01*
X277026Y527975D01*
X276796Y528233D01*
X276681Y528595D01*
X276758Y528957D01*
X276949Y529267D01*
X277294Y529473D01*
X277754Y529577D01*
X278023Y529783D01*
X278138Y530145D01*
X278061Y530507D01*
X277869Y530765D01*
X277601Y530920D01*
X277333D01*
X277064Y530817D01*
X276834Y530558D01*
G01X274884Y528853D02*
X273888D01*
G01X272014Y527820D02*
Y530920D01*
X270558D01*
G01X271094Y529422D02*
X272014D01*
G01X268646Y530920D02*
X267726D01*
G01X268186D02*
Y527820D01*
G01X268646D02*
X267726D01*
G01X265086Y530920D02*
Y527820D01*
G01X265968Y530920D02*
X264204D01*
G01X290653Y702820D02*
Y705920D01*
X289733D01*
X289426Y705765D01*
X289196Y705403D01*
X289119Y704990D01*
X289196Y704577D01*
X289388Y704267D01*
X289733Y704112D01*
X290653D01*
G01X287553Y702820D02*
Y705920D01*
X286594D01*
X286288Y705765D01*
X286096Y705558D01*
X286019Y705145D01*
X286096Y704732D01*
X286326Y704473D01*
X286594Y704318D01*
X287553D01*
G01X286594D02*
X286019Y702820D01*
G01X282919D02*
X284453D01*
Y705920D01*
X282919D01*
G01X283533Y704422D02*
X284453D01*
G01X281391Y703233D02*
X281084Y702975D01*
X280739Y702820D01*
X280433D01*
X280126Y702975D01*
X279896Y703233D01*
X279781Y703595D01*
X279858Y703957D01*
X280049Y704267D01*
X280394Y704473D01*
X280854Y704577D01*
X281123Y704783D01*
X281238Y705145D01*
X281161Y705507D01*
X280969Y705765D01*
X280701Y705920D01*
X280433D01*
X280164Y705817D01*
X279934Y705558D01*
G01X278291Y703233D02*
X277984Y702975D01*
X277639Y702820D01*
X277333D01*
X277026Y702975D01*
X276796Y703233D01*
X276681Y703595D01*
X276758Y703957D01*
X276949Y704267D01*
X277294Y704473D01*
X277754Y704577D01*
X278023Y704783D01*
X278138Y705145D01*
X278061Y705507D01*
X277869Y705765D01*
X277601Y705920D01*
X277333D01*
X277064Y705817D01*
X276834Y705558D01*
G01X274884Y703853D02*
X273888D01*
G01X272014Y702820D02*
Y705920D01*
X270558D01*
G01X271094Y704422D02*
X272014D01*
G01X268646Y705920D02*
X267726D01*
G01X268186D02*
Y702820D01*
G01X268646D02*
X267726D01*
G01X265086Y705920D02*
Y702820D01*
G01X265968Y705920D02*
X264204D01*
G01X364986Y827165D02*
G03I-57900J0D01*
G01X290652Y1227820D02*
Y1230920D01*
X289732D01*
X289425Y1230765D01*
X289195Y1230403D01*
X289118Y1229990D01*
X289195Y1229577D01*
X289387Y1229267D01*
X289732Y1229112D01*
X290652D01*
G01X287552Y1227820D02*
Y1230920D01*
X286593D01*
X286287Y1230765D01*
X286095Y1230558D01*
X286018Y1230145D01*
X286095Y1229732D01*
X286325Y1229473D01*
X286593Y1229318D01*
X287552D01*
G01X286593D02*
X286018Y1227820D01*
G01X282918D02*
X284452D01*
Y1230920D01*
X282918D01*
G01X283532Y1229422D02*
X284452D01*
G01X281390Y1228233D02*
X281083Y1227975D01*
X280738Y1227820D01*
X280432D01*
X280125Y1227975D01*
X279895Y1228233D01*
X279780Y1228595D01*
X279857Y1228957D01*
X280048Y1229267D01*
X280393Y1229473D01*
X280853Y1229577D01*
X281122Y1229783D01*
X281237Y1230145D01*
X281160Y1230507D01*
X280968Y1230765D01*
X280700Y1230920D01*
X280432D01*
X280163Y1230817D01*
X279933Y1230558D01*
G01X278290Y1228233D02*
X277983Y1227975D01*
X277638Y1227820D01*
X277332D01*
X277025Y1227975D01*
X276795Y1228233D01*
X276680Y1228595D01*
X276757Y1228957D01*
X276948Y1229267D01*
X277293Y1229473D01*
X277753Y1229577D01*
X278022Y1229783D01*
X278137Y1230145D01*
X278060Y1230507D01*
X277868Y1230765D01*
X277600Y1230920D01*
X277332D01*
X277063Y1230817D01*
X276833Y1230558D01*
G01X274883Y1228853D02*
X273887D01*
G01X272013Y1227820D02*
Y1230920D01*
X270557D01*
G01X271093Y1229422D02*
X272013D01*
G01X268645Y1230920D02*
X267725D01*
G01X268185D02*
Y1227820D01*
G01X268645D02*
X267725D01*
G01X265085Y1230920D02*
Y1227820D01*
G01X265967Y1230920D02*
X264203D01*
G01X364986Y1343504D02*
G03I-57900J0D01*
G01X290652Y1402820D02*
Y1405920D01*
X289732D01*
X289425Y1405765D01*
X289195Y1405403D01*
X289118Y1404990D01*
X289195Y1404577D01*
X289387Y1404267D01*
X289732Y1404112D01*
X290652D01*
G01X287552Y1402820D02*
Y1405920D01*
X286593D01*
X286287Y1405765D01*
X286095Y1405558D01*
X286018Y1405145D01*
X286095Y1404732D01*
X286325Y1404473D01*
X286593Y1404318D01*
X287552D01*
G01X286593D02*
X286018Y1402820D01*
G01X282918D02*
X284452D01*
Y1405920D01*
X282918D01*
G01X283532Y1404422D02*
X284452D01*
G01X281390Y1403233D02*
X281083Y1402975D01*
X280738Y1402820D01*
X280432D01*
X280125Y1402975D01*
X279895Y1403233D01*
X279780Y1403595D01*
X279857Y1403957D01*
X280048Y1404267D01*
X280393Y1404473D01*
X280853Y1404577D01*
X281122Y1404783D01*
X281237Y1405145D01*
X281160Y1405507D01*
X280968Y1405765D01*
X280700Y1405920D01*
X280432D01*
X280163Y1405817D01*
X279933Y1405558D01*
G01X278290Y1403233D02*
X277983Y1402975D01*
X277638Y1402820D01*
X277332D01*
X277025Y1402975D01*
X276795Y1403233D01*
X276680Y1403595D01*
X276757Y1403957D01*
X276948Y1404267D01*
X277293Y1404473D01*
X277753Y1404577D01*
X278022Y1404783D01*
X278137Y1405145D01*
X278060Y1405507D01*
X277868Y1405765D01*
X277600Y1405920D01*
X277332D01*
X277063Y1405817D01*
X276833Y1405558D01*
G01X274883Y1403853D02*
X273887D01*
G01X272013Y1402820D02*
Y1405920D01*
X270557D01*
G01X271093Y1404422D02*
X272013D01*
G01X268645Y1405920D02*
X267725D01*
G01X268185D02*
Y1402820D01*
G01X268645D02*
X267725D01*
G01X265085Y1405920D02*
Y1402820D01*
G01X265967Y1405920D02*
X264203D01*
G01X290652Y1577820D02*
Y1580920D01*
X289732D01*
X289425Y1580765D01*
X289195Y1580403D01*
X289118Y1579990D01*
X289195Y1579577D01*
X289387Y1579267D01*
X289732Y1579112D01*
X290652D01*
G01X287552Y1577820D02*
Y1580920D01*
X286593D01*
X286287Y1580765D01*
X286095Y1580558D01*
X286018Y1580145D01*
X286095Y1579732D01*
X286325Y1579473D01*
X286593Y1579318D01*
X287552D01*
G01X286593D02*
X286018Y1577820D01*
G01X282918D02*
X284452D01*
Y1580920D01*
X282918D01*
G01X283532Y1579422D02*
X284452D01*
G01X281390Y1578233D02*
X281083Y1577975D01*
X280738Y1577820D01*
X280432D01*
X280125Y1577975D01*
X279895Y1578233D01*
X279780Y1578595D01*
X279857Y1578957D01*
X280048Y1579267D01*
X280393Y1579473D01*
X280853Y1579577D01*
X281122Y1579783D01*
X281237Y1580145D01*
X281160Y1580507D01*
X280968Y1580765D01*
X280700Y1580920D01*
X280432D01*
X280163Y1580817D01*
X279933Y1580558D01*
G01X278290Y1578233D02*
X277983Y1577975D01*
X277638Y1577820D01*
X277332D01*
X277025Y1577975D01*
X276795Y1578233D01*
X276680Y1578595D01*
X276757Y1578957D01*
X276948Y1579267D01*
X277293Y1579473D01*
X277753Y1579577D01*
X278022Y1579783D01*
X278137Y1580145D01*
X278060Y1580507D01*
X277868Y1580765D01*
X277600Y1580920D01*
X277332D01*
X277063Y1580817D01*
X276833Y1580558D01*
G01X274883Y1578853D02*
X273887D01*
G01X272013Y1577820D02*
Y1580920D01*
X270557D01*
G01X271093Y1579422D02*
X272013D01*
G01X268645Y1580920D02*
X267725D01*
G01X268185D02*
Y1577820D01*
G01X268645D02*
X267725D01*
G01X265085Y1580920D02*
Y1577820D01*
G01X265967Y1580920D02*
X264203D01*
G01X283823Y1746525D02*
G03X364986Y1693504I23265J-53019D01*
G01X290652Y1752820D02*
Y1755920D01*
X289732D01*
X289425Y1755765D01*
X289195Y1755403D01*
X289118Y1754990D01*
X289195Y1754577D01*
X289387Y1754267D01*
X289732Y1754112D01*
X290652D01*
G01X287552Y1752820D02*
Y1755920D01*
X286593D01*
X286287Y1755765D01*
X286095Y1755558D01*
X286018Y1755145D01*
X286095Y1754732D01*
X286325Y1754473D01*
X286593Y1754318D01*
X287552D01*
G01X286593D02*
X286018Y1752820D01*
G01X282918D02*
X284452D01*
Y1755920D01*
X282918D01*
G01X283532Y1754422D02*
X284452D01*
G01X281390Y1753233D02*
X281083Y1752975D01*
X280738Y1752820D01*
X280432D01*
X280125Y1752975D01*
X279895Y1753233D01*
X279780Y1753595D01*
X279857Y1753957D01*
X280048Y1754267D01*
X280393Y1754473D01*
X280853Y1754577D01*
X281122Y1754783D01*
X281237Y1755145D01*
X281160Y1755507D01*
X280968Y1755765D01*
X280700Y1755920D01*
X280432D01*
X280163Y1755817D01*
X279933Y1755558D01*
G01X278290Y1753233D02*
X277983Y1752975D01*
X277638Y1752820D01*
X277332D01*
X277025Y1752975D01*
X276795Y1753233D01*
X276680Y1753595D01*
X276757Y1753957D01*
X276948Y1754267D01*
X277293Y1754473D01*
X277753Y1754577D01*
X278022Y1754783D01*
X278137Y1755145D01*
X278060Y1755507D01*
X277868Y1755765D01*
X277600Y1755920D01*
X277332D01*
X277063Y1755817D01*
X276833Y1755558D01*
G01X274883Y1753853D02*
X273887D01*
G01X272013Y1752820D02*
Y1755920D01*
X270557D01*
G01X271093Y1754422D02*
X272013D01*
G01X268645Y1755920D02*
X267725D01*
G01X268185D02*
Y1752820D01*
G01X268645D02*
X267725D01*
G01X265085Y1755920D02*
Y1752820D01*
G01X265967Y1755920D02*
X264203D01*
G01X290652Y1927820D02*
Y1930920D01*
X289732D01*
X289425Y1930765D01*
X289195Y1930403D01*
X289118Y1929990D01*
X289195Y1929577D01*
X289387Y1929267D01*
X289732Y1929112D01*
X290652D01*
G01X287552Y1927820D02*
Y1930920D01*
X286593D01*
X286287Y1930765D01*
X286095Y1930558D01*
X286018Y1930145D01*
X286095Y1929732D01*
X286325Y1929473D01*
X286593Y1929318D01*
X287552D01*
G01X286593D02*
X286018Y1927820D01*
G01X282918D02*
X284452D01*
Y1930920D01*
X282918D01*
G01X283532Y1929422D02*
X284452D01*
G01X281390Y1928233D02*
X281083Y1927975D01*
X280738Y1927820D01*
X280432D01*
X280125Y1927975D01*
X279895Y1928233D01*
X279780Y1928595D01*
X279857Y1928957D01*
X280048Y1929267D01*
X280393Y1929473D01*
X280853Y1929577D01*
X281122Y1929783D01*
X281237Y1930145D01*
X281160Y1930507D01*
X280968Y1930765D01*
X280700Y1930920D01*
X280432D01*
X280163Y1930817D01*
X279933Y1930558D01*
G01X278290Y1928233D02*
X277983Y1927975D01*
X277638Y1927820D01*
X277332D01*
X277025Y1927975D01*
X276795Y1928233D01*
X276680Y1928595D01*
X276757Y1928957D01*
X276948Y1929267D01*
X277293Y1929473D01*
X277753Y1929577D01*
X278022Y1929783D01*
X278137Y1930145D01*
X278060Y1930507D01*
X277868Y1930765D01*
X277600Y1930920D01*
X277332D01*
X277063Y1930817D01*
X276833Y1930558D01*
G01X274883Y1928853D02*
X273887D01*
G01X272013Y1927820D02*
Y1930920D01*
X270557D01*
G01X271093Y1929422D02*
X272013D01*
G01X268645Y1930920D02*
X267725D01*
G01X268185D02*
Y1927820D01*
G01X268645D02*
X267725D01*
G01X265085Y1930920D02*
Y1927820D01*
G01X265967Y1930920D02*
X264203D01*
G01X364987Y2043503D02*
G03I-57900J0D01*
G01X300976Y4295D02*
Y7395D01*
X300056D01*
X299749Y7240D01*
X299519Y6878D01*
X299442Y6465D01*
X299519Y6052D01*
X299711Y5742D01*
X300056Y5587D01*
X300976D01*
G01X297876Y4295D02*
Y7395D01*
X296917D01*
X296611Y7240D01*
X296419Y7033D01*
X296342Y6620D01*
X296419Y6207D01*
X296649Y5948D01*
X296917Y5793D01*
X297876D01*
G01X296917D02*
X296342Y4295D01*
G01X293242D02*
X294776D01*
Y7395D01*
X293242D01*
G01X293856Y5897D02*
X294776D01*
G01X291714Y4708D02*
X291407Y4450D01*
X291062Y4295D01*
X290756D01*
X290449Y4450D01*
X290219Y4708D01*
X290104Y5070D01*
X290181Y5432D01*
X290372Y5742D01*
X290717Y5948D01*
X291177Y6052D01*
X291446Y6258D01*
X291561Y6620D01*
X291484Y6982D01*
X291292Y7240D01*
X291024Y7395D01*
X290756D01*
X290487Y7292D01*
X290257Y7033D01*
G01X288614Y4708D02*
X288307Y4450D01*
X287962Y4295D01*
X287656D01*
X287349Y4450D01*
X287119Y4708D01*
X287004Y5070D01*
X287081Y5432D01*
X287272Y5742D01*
X287617Y5948D01*
X288077Y6052D01*
X288346Y6258D01*
X288461Y6620D01*
X288384Y6982D01*
X288192Y7240D01*
X287924Y7395D01*
X287656D01*
X287387Y7292D01*
X287157Y7033D01*
G01X285207Y5328D02*
X284211D01*
G01X282337Y4295D02*
Y7395D01*
X280881D01*
G01X281417Y5897D02*
X282337D01*
G01X278969Y7395D02*
X278049D01*
G01X278509D02*
Y4295D01*
G01X278969D02*
X278049D01*
G01X275409Y7395D02*
Y4295D01*
G01X276291Y7395D02*
X274527D01*
G01X364986Y1693504D02*
G03X288897Y1748473I-57900J0D01*
G01X320546Y308267D02*
G03I-13460J0D01*
G01X293636Y1883071D02*
Y1885021D01*
G02X307086Y1898471I13450J0D01*
G02X320536Y1885021I0J-13450D01*
G01Y1881121D01*
G02X307086Y1867671I-13450J0D01*
G02X293636Y1881121I0J13450D01*
G01Y1883071D01*
G01X328600Y-123333D02*
X329200Y-122533D01*
X329900Y-122133D01*
X330700Y-122000D01*
X331700Y-122267D01*
X332400Y-122933D01*
X332600Y-123733D01*
X332500Y-124534D01*
X332100Y-125200D01*
X330100Y-126533D01*
X329200Y-127467D01*
X328600Y-128800D01*
X328400Y-130000D01*
X332600D01*
G01X338500Y-122000D02*
X337700Y-122267D01*
X337100Y-122933D01*
X336700Y-123733D01*
X336400Y-124800D01*
X336300Y-126000D01*
X336400Y-127200D01*
X336700Y-128267D01*
X337100Y-129067D01*
X337700Y-129733D01*
X338500Y-130000D01*
X339300Y-129733D01*
X339900Y-129067D01*
X340300Y-128267D01*
X340600Y-127200D01*
X340700Y-126000D01*
X340600Y-124800D01*
X340300Y-123733D01*
X339900Y-122933D01*
X339300Y-122267D01*
X338500Y-122000D01*
G01X346500Y-130000D02*
Y-122000D01*
X345300Y-123600D01*
G01Y-130000D02*
X347700D01*
G01X352600Y-123333D02*
X353200Y-122533D01*
X353900Y-122133D01*
X354700Y-122000D01*
X355700Y-122267D01*
X356400Y-122933D01*
X356600Y-123733D01*
X356500Y-124534D01*
X356100Y-125200D01*
X354100Y-126533D01*
X353200Y-127467D01*
X352600Y-128800D01*
X352400Y-130000D01*
X356600D01*
G01X360700Y-130267D02*
X364300Y-122000D01*
G01X370500D02*
X369700Y-122267D01*
X369100Y-122933D01*
X368700Y-123733D01*
X368400Y-124800D01*
X368300Y-126000D01*
X368400Y-127200D01*
X368700Y-128267D01*
X369100Y-129067D01*
X369700Y-129733D01*
X370500Y-130000D01*
X371300Y-129733D01*
X371900Y-129067D01*
X372300Y-128267D01*
X372600Y-127200D01*
X372700Y-126000D01*
X372600Y-124800D01*
X372300Y-123733D01*
X371900Y-122933D01*
X371300Y-122267D01*
X370500Y-122000D01*
G01X376800Y-129067D02*
X377500Y-129733D01*
X378300Y-130000D01*
X379100Y-129733D01*
X379800Y-128934D01*
X380300Y-127733D01*
X380500Y-126533D01*
Y-125067D01*
X380300Y-123867D01*
X379800Y-122800D01*
X379200Y-122267D01*
X378500Y-122000D01*
X377700Y-122267D01*
X377100Y-122800D01*
X376700Y-123600D01*
X376500Y-124667D01*
X376700Y-125600D01*
X377200Y-126533D01*
X377800Y-127067D01*
X378500Y-127200D01*
X379300Y-126934D01*
X379900Y-126267D01*
X380500Y-125067D01*
G01X384700Y-130267D02*
X388300Y-122000D01*
G01X392600Y-123333D02*
X393200Y-122533D01*
X393900Y-122133D01*
X394700Y-122000D01*
X395700Y-122267D01*
X396400Y-122933D01*
X396600Y-123733D01*
X396500Y-124534D01*
X396100Y-125200D01*
X394100Y-126533D01*
X393200Y-127467D01*
X392600Y-128800D01*
X392400Y-130000D01*
X396600D01*
G01X402500D02*
X403200Y-129867D01*
X404000Y-129467D01*
X404500Y-128800D01*
X404700Y-127867D01*
X404500Y-126934D01*
X403900Y-126133D01*
X403000Y-125733D01*
X402000D01*
X401400Y-125467D01*
X400900Y-124800D01*
X400700Y-123867D01*
X401000Y-122933D01*
X401700Y-122267D01*
X402500Y-122000D01*
X403300Y-122267D01*
X404000Y-122933D01*
X404300Y-123867D01*
X404100Y-124800D01*
X403600Y-125467D01*
X403000Y-125733D01*
X402000D01*
X401100Y-126133D01*
X400500Y-126934D01*
X400300Y-127867D01*
X400500Y-128800D01*
X401000Y-129467D01*
X401800Y-129867D01*
X402500Y-130000D01*
G01X328300Y-105000D02*
Y-97000D01*
X330300D01*
X331100Y-97400D01*
X331700Y-97933D01*
X332200Y-98733D01*
X332600Y-99667D01*
X332700Y-101000D01*
X332600Y-102333D01*
X332200Y-103267D01*
X331700Y-104067D01*
X331100Y-104600D01*
X330300Y-105000D01*
X328300D01*
G01X336000D02*
X338500Y-97000D01*
X341000Y-105000D01*
G01X340100Y-102200D02*
X336900D01*
G01X346500Y-97000D02*
X345700Y-97267D01*
X345100Y-97933D01*
X344700Y-98733D01*
X344400Y-99800D01*
X344300Y-101000D01*
X344400Y-102200D01*
X344700Y-103267D01*
X345100Y-104067D01*
X345700Y-104733D01*
X346500Y-105000D01*
X347300Y-104733D01*
X347900Y-104067D01*
X348300Y-103267D01*
X348600Y-102200D01*
X348700Y-101000D01*
X348600Y-99800D01*
X348300Y-98733D01*
X347900Y-97933D01*
X347300Y-97267D01*
X346500Y-97000D01*
G01X354500D02*
Y-105000D01*
G01X352200Y-97000D02*
X356800D01*
G01X360600Y-101667D02*
X361300Y-100733D01*
X361900Y-100200D01*
X362700Y-99933D01*
X363400Y-100200D01*
X363900Y-100733D01*
X364300Y-101533D01*
X364400Y-102467D01*
X364300Y-103267D01*
X363900Y-104067D01*
X363300Y-104733D01*
X362600Y-105000D01*
X361800Y-104733D01*
X361100Y-103934D01*
X360700Y-102733D01*
X360600Y-101400D01*
X360800Y-99667D01*
X361100Y-98733D01*
X361600Y-97800D01*
X362300Y-97133D01*
X363000Y-97000D01*
X363700Y-97267D01*
X364200Y-97933D01*
G01X367900Y-105000D02*
Y-97000D01*
X370500Y-103667D01*
X373100Y-97000D01*
Y-105000D01*
G01X378500Y-97000D02*
Y-105000D01*
G01X376200Y-97000D02*
X380800D01*
G01X387300Y-100733D02*
X387700Y-100333D01*
X388000Y-99667D01*
X388200Y-98733D01*
X388000Y-97933D01*
X387600Y-97400D01*
X386900Y-97000D01*
X384200D01*
Y-105000D01*
X387500D01*
X388200Y-104467D01*
X388600Y-103667D01*
X388800Y-102733D01*
X388600Y-101800D01*
X388000Y-101000D01*
X387300Y-100733D01*
X384200D01*
G01X394500Y-105000D02*
X395200Y-104867D01*
X396000Y-104467D01*
X396500Y-103800D01*
X396700Y-102867D01*
X396500Y-101934D01*
X395900Y-101133D01*
X395000Y-100733D01*
X394000D01*
X393400Y-100467D01*
X392900Y-99800D01*
X392700Y-98867D01*
X393000Y-97933D01*
X393700Y-97267D01*
X394500Y-97000D01*
X395300Y-97267D01*
X396000Y-97933D01*
X396300Y-98867D01*
X396100Y-99800D01*
X395600Y-100467D01*
X395000Y-100733D01*
X394000D01*
X393100Y-101133D01*
X392500Y-101934D01*
X392300Y-102867D01*
X392500Y-103800D01*
X393000Y-104467D01*
X393800Y-104867D01*
X394500Y-105000D01*
G01X400300D02*
Y-97000D01*
X402300D01*
X403100Y-97400D01*
X403700Y-97933D01*
X404200Y-98733D01*
X404600Y-99667D01*
X404700Y-101000D01*
X404600Y-102333D01*
X404200Y-103267D01*
X403700Y-104067D01*
X403100Y-104600D01*
X402300Y-105000D01*
X400300D01*
G01X410500Y-97000D02*
X409700Y-97267D01*
X409100Y-97933D01*
X408700Y-98733D01*
X408400Y-99800D01*
X408300Y-101000D01*
X408400Y-102200D01*
X408700Y-103267D01*
X409100Y-104067D01*
X409700Y-104733D01*
X410500Y-105000D01*
X411300Y-104733D01*
X411900Y-104067D01*
X412300Y-103267D01*
X412600Y-102200D01*
X412700Y-101000D01*
X412600Y-99800D01*
X412300Y-98733D01*
X411900Y-97933D01*
X411300Y-97267D01*
X410500Y-97000D01*
G01X326961Y8077D02*
Y11177D01*
X326041D01*
X325734Y11022D01*
X325504Y10660D01*
X325427Y10247D01*
X325504Y9834D01*
X325696Y9524D01*
X326041Y9369D01*
X326961D01*
G01X323094Y8077D02*
Y11177D01*
X323554Y10557D01*
G01Y8077D02*
X322634D01*
G01X320071D02*
X319994Y8749D01*
X319879Y9317D01*
X319726Y9834D01*
X319534Y10402D01*
X319227Y11177D01*
X320761D01*
G01X344388Y8508D02*
X344081Y8250D01*
X343736Y8095D01*
X343430D01*
X343123Y8250D01*
X342893Y8508D01*
X342778Y8870D01*
X342855Y9232D01*
X343046Y9542D01*
X343391Y9748D01*
X343851Y9852D01*
X344120Y10058D01*
X344235Y10420D01*
X344158Y10782D01*
X343966Y11040D01*
X343698Y11195D01*
X343430D01*
X343161Y11092D01*
X342931Y10833D01*
G01X340483Y8095D02*
Y11195D01*
X340943Y10575D01*
G01Y8095D02*
X340023D01*
G01X338111Y10678D02*
X337881Y10988D01*
X337613Y11143D01*
X337306Y11195D01*
X336923Y11092D01*
X336655Y10833D01*
X336578Y10523D01*
X336616Y10213D01*
X336770Y9955D01*
X337536Y9438D01*
X337881Y9077D01*
X338111Y8560D01*
X338188Y8095D01*
X336578D01*
G01X340844Y43089D02*
X340537Y42831D01*
X340192Y42676D01*
X339886D01*
X339579Y42831D01*
X339349Y43089D01*
X339234Y43451D01*
X339311Y43813D01*
X339502Y44123D01*
X339847Y44329D01*
X340307Y44433D01*
X340576Y44639D01*
X340691Y45001D01*
X340614Y45363D01*
X340422Y45621D01*
X340154Y45776D01*
X339886D01*
X339617Y45673D01*
X339387Y45414D01*
G01X336939Y42676D02*
Y45776D01*
X337399Y45156D01*
G01Y42676D02*
X336479D01*
G01X328576Y42696D02*
Y45796D01*
X327656D01*
X327349Y45641D01*
X327119Y45279D01*
X327042Y44866D01*
X327119Y44453D01*
X327311Y44143D01*
X327656Y43988D01*
X328576D01*
G01X324709Y42696D02*
Y45796D01*
X325169Y45176D01*
G01Y42696D02*
X324249D01*
G01X322337Y43988D02*
X322069Y44349D01*
X321839Y44556D01*
X321532Y44659D01*
X321264Y44556D01*
X321072Y44349D01*
X320919Y44039D01*
X320881Y43678D01*
X320919Y43368D01*
X321072Y43058D01*
X321302Y42799D01*
X321571Y42696D01*
X321877Y42799D01*
X322146Y43109D01*
X322299Y43574D01*
X322337Y44091D01*
X322261Y44763D01*
X322146Y45124D01*
X321954Y45486D01*
X321686Y45744D01*
X321417Y45796D01*
X321149Y45693D01*
X320957Y45434D01*
G01X325794Y183541D02*
Y186641D01*
X324874D01*
X324567Y186486D01*
X324337Y186124D01*
X324260Y185711D01*
X324337Y185298D01*
X324529Y184988D01*
X324874Y184833D01*
X325794D01*
G01X321927Y183541D02*
Y186641D01*
X322387Y186021D01*
G01Y183541D02*
X321467D01*
G01X318904D02*
X318827Y184213D01*
X318712Y184781D01*
X318559Y185298D01*
X318367Y185866D01*
X318060Y186641D01*
X319594D01*
G01X340673Y183837D02*
X340366Y183579D01*
X340021Y183424D01*
X339715D01*
X339408Y183579D01*
X339178Y183837D01*
X339063Y184199D01*
X339140Y184561D01*
X339331Y184871D01*
X339676Y185077D01*
X340136Y185181D01*
X340405Y185387D01*
X340520Y185749D01*
X340443Y186111D01*
X340251Y186369D01*
X339983Y186524D01*
X339715D01*
X339446Y186421D01*
X339216Y186162D01*
G01X336768Y183424D02*
Y186524D01*
X337228Y185904D01*
G01Y183424D02*
X336308D01*
G01X334396Y186007D02*
X334166Y186317D01*
X333898Y186472D01*
X333591Y186524D01*
X333208Y186421D01*
X332940Y186162D01*
X332863Y185852D01*
X332901Y185542D01*
X333055Y185284D01*
X333821Y184767D01*
X334166Y184406D01*
X334396Y183889D01*
X334473Y183424D01*
X332863D01*
G01X341018Y218688D02*
X340711Y218430D01*
X340366Y218275D01*
X340060D01*
X339753Y218430D01*
X339523Y218688D01*
X339408Y219050D01*
X339485Y219412D01*
X339676Y219722D01*
X340021Y219928D01*
X340481Y220032D01*
X340750Y220238D01*
X340865Y220600D01*
X340788Y220962D01*
X340596Y221220D01*
X340328Y221375D01*
X340060D01*
X339791Y221272D01*
X339561Y221013D01*
G01X337113Y218275D02*
Y221375D01*
X337573Y220755D01*
G01Y218275D02*
X336653D01*
G01X327276Y218294D02*
Y221394D01*
X326356D01*
X326049Y221239D01*
X325819Y220877D01*
X325742Y220464D01*
X325819Y220051D01*
X326011Y219741D01*
X326356Y219586D01*
X327276D01*
G01X323409Y218294D02*
Y221394D01*
X323869Y220774D01*
G01Y218294D02*
X322949D01*
G01X321037Y219586D02*
X320769Y219947D01*
X320539Y220154D01*
X320232Y220257D01*
X319964Y220154D01*
X319772Y219947D01*
X319619Y219637D01*
X319581Y219276D01*
X319619Y218966D01*
X319772Y218656D01*
X320002Y218397D01*
X320271Y218294D01*
X320577Y218397D01*
X320846Y218707D01*
X320999Y219172D01*
X321037Y219689D01*
X320961Y220361D01*
X320846Y220722D01*
X320654Y221084D01*
X320386Y221342D01*
X320117Y221394D01*
X319849Y221291D01*
X319657Y221032D01*
G01X326557Y358590D02*
Y361690D01*
X325637D01*
X325330Y361535D01*
X325100Y361173D01*
X325023Y360760D01*
X325100Y360347D01*
X325292Y360037D01*
X325637Y359882D01*
X326557D01*
G01X322690Y358590D02*
Y361690D01*
X323150Y361070D01*
G01Y358590D02*
X322230D01*
G01X319667D02*
X319590Y359262D01*
X319475Y359830D01*
X319322Y360347D01*
X319130Y360915D01*
X318823Y361690D01*
X320357D01*
G01X342910Y358886D02*
X342603Y358628D01*
X342258Y358473D01*
X341952D01*
X341645Y358628D01*
X341415Y358886D01*
X341300Y359248D01*
X341377Y359610D01*
X341568Y359920D01*
X341913Y360126D01*
X342373Y360230D01*
X342642Y360436D01*
X342757Y360798D01*
X342680Y361160D01*
X342488Y361418D01*
X342220Y361573D01*
X341952D01*
X341683Y361470D01*
X341453Y361211D01*
G01X339005Y358473D02*
Y361573D01*
X339465Y360953D01*
G01Y358473D02*
X338545D01*
G01X336633Y361056D02*
X336403Y361366D01*
X336135Y361521D01*
X335828Y361573D01*
X335445Y361470D01*
X335177Y361211D01*
X335100Y360901D01*
X335138Y360591D01*
X335292Y360333D01*
X336058Y359816D01*
X336403Y359455D01*
X336633Y358938D01*
X336710Y358473D01*
X335100D01*
G01X339502Y393602D02*
X339195Y393344D01*
X338850Y393189D01*
X338544D01*
X338237Y393344D01*
X338007Y393602D01*
X337892Y393964D01*
X337969Y394326D01*
X338160Y394636D01*
X338505Y394842D01*
X338965Y394946D01*
X339234Y395152D01*
X339349Y395514D01*
X339272Y395876D01*
X339080Y396134D01*
X338812Y396289D01*
X338544D01*
X338275Y396186D01*
X338045Y395927D01*
G01X335597Y393189D02*
Y396289D01*
X336057Y395669D01*
G01Y393189D02*
X335137D01*
G01X326564Y393344D02*
Y396444D01*
X325644D01*
X325337Y396289D01*
X325107Y395927D01*
X325030Y395514D01*
X325107Y395101D01*
X325299Y394791D01*
X325644Y394636D01*
X326564D01*
G01X322697Y393344D02*
Y396444D01*
X323157Y395824D01*
G01Y393344D02*
X322237D01*
G01X320325Y394636D02*
X320057Y394997D01*
X319827Y395204D01*
X319520Y395307D01*
X319252Y395204D01*
X319060Y394997D01*
X318907Y394687D01*
X318869Y394326D01*
X318907Y394016D01*
X319060Y393706D01*
X319290Y393447D01*
X319559Y393344D01*
X319865Y393447D01*
X320134Y393757D01*
X320287Y394222D01*
X320325Y394739D01*
X320249Y395411D01*
X320134Y395772D01*
X319942Y396134D01*
X319674Y396392D01*
X319405Y396444D01*
X319137Y396341D01*
X318945Y396082D01*
G01X326291Y532843D02*
Y535943D01*
X325371D01*
X325064Y535788D01*
X324834Y535426D01*
X324757Y535013D01*
X324834Y534600D01*
X325026Y534290D01*
X325371Y534135D01*
X326291D01*
G01X322424Y532843D02*
Y535943D01*
X322884Y535323D01*
G01Y532843D02*
X321964D01*
G01X319401D02*
X319324Y533515D01*
X319209Y534083D01*
X319056Y534600D01*
X318864Y535168D01*
X318557Y535943D01*
X320091D01*
G01X341035Y533674D02*
X340728Y533416D01*
X340383Y533261D01*
X340077D01*
X339770Y533416D01*
X339540Y533674D01*
X339425Y534036D01*
X339502Y534398D01*
X339693Y534708D01*
X340038Y534914D01*
X340498Y535018D01*
X340767Y535224D01*
X340882Y535586D01*
X340805Y535948D01*
X340613Y536206D01*
X340345Y536361D01*
X340077D01*
X339808Y536258D01*
X339578Y535999D01*
G01X337130Y533261D02*
Y536361D01*
X337590Y535741D01*
G01Y533261D02*
X336670D01*
G01X334758Y535844D02*
X334528Y536154D01*
X334260Y536309D01*
X333953Y536361D01*
X333570Y536258D01*
X333302Y535999D01*
X333225Y535689D01*
X333263Y535379D01*
X333417Y535121D01*
X334183Y534604D01*
X334528Y534243D01*
X334758Y533726D01*
X334835Y533261D01*
X333225D01*
G01X341421Y568669D02*
X341114Y568411D01*
X340769Y568256D01*
X340463D01*
X340156Y568411D01*
X339926Y568669D01*
X339811Y569031D01*
X339888Y569393D01*
X340079Y569703D01*
X340424Y569909D01*
X340884Y570013D01*
X341153Y570219D01*
X341268Y570581D01*
X341191Y570943D01*
X340999Y571201D01*
X340731Y571356D01*
X340463D01*
X340194Y571253D01*
X339964Y570994D01*
G01X337516Y568256D02*
Y571356D01*
X337976Y570736D01*
G01Y568256D02*
X337056D01*
G01X327143Y568008D02*
Y571108D01*
X326223D01*
X325916Y570953D01*
X325686Y570591D01*
X325609Y570178D01*
X325686Y569765D01*
X325878Y569455D01*
X326223Y569300D01*
X327143D01*
G01X323276Y568008D02*
Y571108D01*
X323736Y570488D01*
G01Y568008D02*
X322816D01*
G01X320904Y569300D02*
X320636Y569661D01*
X320406Y569868D01*
X320099Y569971D01*
X319831Y569868D01*
X319639Y569661D01*
X319486Y569351D01*
X319448Y568990D01*
X319486Y568680D01*
X319639Y568370D01*
X319869Y568111D01*
X320138Y568008D01*
X320444Y568111D01*
X320713Y568421D01*
X320866Y568886D01*
X320904Y569403D01*
X320828Y570075D01*
X320713Y570436D01*
X320521Y570798D01*
X320253Y571056D01*
X319984Y571108D01*
X319716Y571005D01*
X319524Y570746D01*
G01X325353Y707898D02*
Y710998D01*
X324433D01*
X324126Y710843D01*
X323896Y710481D01*
X323819Y710068D01*
X323896Y709655D01*
X324088Y709345D01*
X324433Y709190D01*
X325353D01*
G01X321486Y707898D02*
Y710998D01*
X321946Y710378D01*
G01Y707898D02*
X321026D01*
G01X318463D02*
X318386Y708570D01*
X318271Y709138D01*
X318118Y709655D01*
X317926Y710223D01*
X317619Y710998D01*
X319153D01*
G01X342913Y708596D02*
X342606Y708338D01*
X342261Y708183D01*
X341955D01*
X341648Y708338D01*
X341418Y708596D01*
X341303Y708958D01*
X341380Y709320D01*
X341571Y709630D01*
X341916Y709836D01*
X342376Y709940D01*
X342645Y710146D01*
X342760Y710508D01*
X342683Y710870D01*
X342491Y711128D01*
X342223Y711283D01*
X341955D01*
X341686Y711180D01*
X341456Y710921D01*
G01X339008Y708183D02*
Y711283D01*
X339468Y710663D01*
G01Y708183D02*
X338548D01*
G01X336636Y710766D02*
X336406Y711076D01*
X336138Y711231D01*
X335831Y711283D01*
X335448Y711180D01*
X335180Y710921D01*
X335103Y710611D01*
X335141Y710301D01*
X335295Y710043D01*
X336061Y709526D01*
X336406Y709165D01*
X336636Y708648D01*
X336713Y708183D01*
X335103D01*
G01X340175Y743446D02*
X339868Y743188D01*
X339523Y743033D01*
X339217D01*
X338910Y743188D01*
X338680Y743446D01*
X338565Y743808D01*
X338642Y744170D01*
X338833Y744480D01*
X339178Y744686D01*
X339638Y744790D01*
X339907Y744996D01*
X340022Y745358D01*
X339945Y745720D01*
X339753Y745978D01*
X339485Y746133D01*
X339217D01*
X338948Y746030D01*
X338718Y745771D01*
G01X336270Y743033D02*
Y746133D01*
X336730Y745513D01*
G01Y743033D02*
X335810D01*
G01X326433Y743455D02*
Y746555D01*
X325513D01*
X325206Y746400D01*
X324976Y746038D01*
X324899Y745625D01*
X324976Y745212D01*
X325168Y744902D01*
X325513Y744747D01*
X326433D01*
G01X322566Y743455D02*
Y746555D01*
X323026Y745935D01*
G01Y743455D02*
X322106D01*
G01X320194Y744747D02*
X319926Y745108D01*
X319696Y745315D01*
X319389Y745418D01*
X319121Y745315D01*
X318929Y745108D01*
X318776Y744798D01*
X318738Y744437D01*
X318776Y744127D01*
X318929Y743817D01*
X319159Y743558D01*
X319428Y743455D01*
X319734Y743558D01*
X320003Y743868D01*
X320156Y744333D01*
X320194Y744850D01*
X320118Y745522D01*
X320003Y745883D01*
X319811Y746245D01*
X319543Y746503D01*
X319274Y746555D01*
X319006Y746452D01*
X318814Y746193D01*
G01X326062Y883771D02*
Y886871D01*
X325142D01*
X324835Y886716D01*
X324605Y886354D01*
X324528Y885941D01*
X324605Y885528D01*
X324797Y885218D01*
X325142Y885063D01*
X326062D01*
G01X322195Y883771D02*
Y886871D01*
X322655Y886251D01*
G01Y883771D02*
X321735D01*
G01X319172D02*
X319095Y884443D01*
X318980Y885011D01*
X318827Y885528D01*
X318635Y886096D01*
X318328Y886871D01*
X319862D01*
G01X342348Y884000D02*
X342041Y883742D01*
X341696Y883587D01*
X341390D01*
X341083Y883742D01*
X340853Y884000D01*
X340738Y884362D01*
X340815Y884724D01*
X341006Y885034D01*
X341351Y885240D01*
X341811Y885344D01*
X342080Y885550D01*
X342195Y885912D01*
X342118Y886274D01*
X341926Y886532D01*
X341658Y886687D01*
X341390D01*
X341121Y886584D01*
X340891Y886325D01*
G01X338443Y883587D02*
Y886687D01*
X338903Y886067D01*
G01Y883587D02*
X337983D01*
G01X336071Y886170D02*
X335841Y886480D01*
X335573Y886635D01*
X335266Y886687D01*
X334883Y886584D01*
X334615Y886325D01*
X334538Y886015D01*
X334576Y885705D01*
X334730Y885447D01*
X335496Y884930D01*
X335841Y884569D01*
X336071Y884052D01*
X336148Y883587D01*
X334538D01*
G01X340347Y918113D02*
X340040Y917855D01*
X339695Y917700D01*
X339389D01*
X339082Y917855D01*
X338852Y918113D01*
X338737Y918475D01*
X338814Y918837D01*
X339005Y919147D01*
X339350Y919353D01*
X339810Y919457D01*
X340079Y919663D01*
X340194Y920025D01*
X340117Y920387D01*
X339925Y920645D01*
X339657Y920800D01*
X339389D01*
X339120Y920697D01*
X338890Y920438D01*
G01X336442Y917700D02*
Y920800D01*
X336902Y920180D01*
G01Y917700D02*
X335982D01*
G01X326336Y917586D02*
Y920686D01*
X325416D01*
X325109Y920531D01*
X324879Y920169D01*
X324802Y919756D01*
X324879Y919343D01*
X325071Y919033D01*
X325416Y918878D01*
X326336D01*
G01X322469Y917586D02*
Y920686D01*
X322929Y920066D01*
G01Y917586D02*
X322009D01*
G01X320097Y918878D02*
X319829Y919239D01*
X319599Y919446D01*
X319292Y919549D01*
X319024Y919446D01*
X318832Y919239D01*
X318679Y918929D01*
X318641Y918568D01*
X318679Y918258D01*
X318832Y917948D01*
X319062Y917689D01*
X319331Y917586D01*
X319637Y917689D01*
X319906Y917999D01*
X320059Y918464D01*
X320097Y918981D01*
X320021Y919653D01*
X319906Y920014D01*
X319714Y920376D01*
X319446Y920634D01*
X319177Y920686D01*
X318909Y920583D01*
X318717Y920324D01*
G01X326425Y1058548D02*
Y1061648D01*
X325505D01*
X325198Y1061493D01*
X324968Y1061131D01*
X324891Y1060718D01*
X324968Y1060305D01*
X325160Y1059995D01*
X325505Y1059840D01*
X326425D01*
G01X322558Y1058548D02*
Y1061648D01*
X323018Y1061028D01*
G01Y1058548D02*
X322098D01*
G01X319535D02*
X319458Y1059220D01*
X319343Y1059788D01*
X319190Y1060305D01*
X318998Y1060873D01*
X318691Y1061648D01*
X320225D01*
G01X344119Y1058575D02*
X343812Y1058317D01*
X343467Y1058162D01*
X343161D01*
X342854Y1058317D01*
X342624Y1058575D01*
X342509Y1058937D01*
X342586Y1059299D01*
X342777Y1059609D01*
X343122Y1059815D01*
X343582Y1059919D01*
X343851Y1060125D01*
X343966Y1060487D01*
X343889Y1060849D01*
X343697Y1061107D01*
X343429Y1061262D01*
X343161D01*
X342892Y1061159D01*
X342662Y1060900D01*
G01X340214Y1058162D02*
Y1061262D01*
X340674Y1060642D01*
G01Y1058162D02*
X339754D01*
G01X337842Y1060745D02*
X337612Y1061055D01*
X337344Y1061210D01*
X337037Y1061262D01*
X336654Y1061159D01*
X336386Y1060900D01*
X336309Y1060590D01*
X336347Y1060280D01*
X336501Y1060022D01*
X337267Y1059505D01*
X337612Y1059144D01*
X337842Y1058627D01*
X337919Y1058162D01*
X336309D01*
G01X339905Y1093558D02*
X339598Y1093300D01*
X339253Y1093145D01*
X338947D01*
X338640Y1093300D01*
X338410Y1093558D01*
X338295Y1093920D01*
X338372Y1094282D01*
X338563Y1094592D01*
X338908Y1094798D01*
X339368Y1094902D01*
X339637Y1095108D01*
X339752Y1095470D01*
X339675Y1095832D01*
X339483Y1096090D01*
X339215Y1096245D01*
X338947D01*
X338678Y1096142D01*
X338448Y1095883D01*
G01X336000Y1093145D02*
Y1096245D01*
X336460Y1095625D01*
G01Y1093145D02*
X335540D01*
G01X326028Y1093031D02*
Y1096131D01*
X325108D01*
X324801Y1095976D01*
X324571Y1095614D01*
X324494Y1095201D01*
X324571Y1094788D01*
X324763Y1094478D01*
X325108Y1094323D01*
X326028D01*
G01X322161Y1093031D02*
Y1096131D01*
X322621Y1095511D01*
G01Y1093031D02*
X321701D01*
G01X319789Y1094323D02*
X319521Y1094684D01*
X319291Y1094891D01*
X318984Y1094994D01*
X318716Y1094891D01*
X318524Y1094684D01*
X318371Y1094374D01*
X318333Y1094013D01*
X318371Y1093703D01*
X318524Y1093393D01*
X318754Y1093134D01*
X319023Y1093031D01*
X319329Y1093134D01*
X319598Y1093444D01*
X319751Y1093909D01*
X319789Y1094426D01*
X319713Y1095098D01*
X319598Y1095459D01*
X319406Y1095821D01*
X319138Y1096079D01*
X318869Y1096131D01*
X318601Y1096028D01*
X318409Y1095769D01*
G01X326063Y1233201D02*
Y1236301D01*
X325143D01*
X324836Y1236146D01*
X324606Y1235784D01*
X324529Y1235371D01*
X324606Y1234958D01*
X324798Y1234648D01*
X325143Y1234493D01*
X326063D01*
G01X322196Y1233201D02*
Y1236301D01*
X322656Y1235681D01*
G01Y1233201D02*
X321736D01*
G01X319173D02*
X319096Y1233873D01*
X318981Y1234441D01*
X318828Y1234958D01*
X318636Y1235526D01*
X318329Y1236301D01*
X319863D01*
G01X344160Y1233631D02*
X343853Y1233373D01*
X343508Y1233218D01*
X343202D01*
X342895Y1233373D01*
X342665Y1233631D01*
X342550Y1233993D01*
X342627Y1234355D01*
X342818Y1234665D01*
X343163Y1234871D01*
X343623Y1234975D01*
X343892Y1235181D01*
X344007Y1235543D01*
X343930Y1235905D01*
X343738Y1236163D01*
X343470Y1236318D01*
X343202D01*
X342933Y1236215D01*
X342703Y1235956D01*
G01X340255Y1233218D02*
Y1236318D01*
X340715Y1235698D01*
G01Y1233218D02*
X339795D01*
G01X337883Y1235801D02*
X337653Y1236111D01*
X337385Y1236266D01*
X337078Y1236318D01*
X336695Y1236215D01*
X336427Y1235956D01*
X336350Y1235646D01*
X336388Y1235336D01*
X336542Y1235078D01*
X337308Y1234561D01*
X337653Y1234200D01*
X337883Y1233683D01*
X337960Y1233218D01*
X336350D01*
G01X340215Y1268885D02*
X339908Y1268627D01*
X339563Y1268472D01*
X339257D01*
X338950Y1268627D01*
X338720Y1268885D01*
X338605Y1269247D01*
X338682Y1269609D01*
X338873Y1269919D01*
X339218Y1270125D01*
X339678Y1270229D01*
X339947Y1270435D01*
X340062Y1270797D01*
X339985Y1271159D01*
X339793Y1271417D01*
X339525Y1271572D01*
X339257D01*
X338988Y1271469D01*
X338758Y1271210D01*
G01X336310Y1268472D02*
Y1271572D01*
X336770Y1270952D01*
G01Y1268472D02*
X335850D01*
G01X326069Y1268626D02*
Y1271726D01*
X325149D01*
X324842Y1271571D01*
X324612Y1271209D01*
X324535Y1270796D01*
X324612Y1270383D01*
X324804Y1270073D01*
X325149Y1269918D01*
X326069D01*
G01X322202Y1268626D02*
Y1271726D01*
X322662Y1271106D01*
G01Y1268626D02*
X321742D01*
G01X319830Y1269918D02*
X319562Y1270279D01*
X319332Y1270486D01*
X319025Y1270589D01*
X318757Y1270486D01*
X318565Y1270279D01*
X318412Y1269969D01*
X318374Y1269608D01*
X318412Y1269298D01*
X318565Y1268988D01*
X318795Y1268729D01*
X319064Y1268626D01*
X319370Y1268729D01*
X319639Y1269039D01*
X319792Y1269504D01*
X319830Y1270021D01*
X319754Y1270693D01*
X319639Y1271054D01*
X319447Y1271416D01*
X319179Y1271674D01*
X318910Y1271726D01*
X318642Y1271623D01*
X318450Y1271364D01*
G01X326156Y1407453D02*
Y1410553D01*
X325236D01*
X324929Y1410398D01*
X324699Y1410036D01*
X324622Y1409623D01*
X324699Y1409210D01*
X324891Y1408900D01*
X325236Y1408745D01*
X326156D01*
G01X322289Y1407453D02*
Y1410553D01*
X322749Y1409933D01*
G01Y1407453D02*
X321829D01*
G01X319266D02*
X319189Y1408125D01*
X319074Y1408693D01*
X318921Y1409210D01*
X318729Y1409778D01*
X318422Y1410553D01*
X319956D01*
G01X344252Y1408420D02*
X343945Y1408162D01*
X343600Y1408007D01*
X343294D01*
X342987Y1408162D01*
X342757Y1408420D01*
X342642Y1408782D01*
X342719Y1409144D01*
X342910Y1409454D01*
X343255Y1409660D01*
X343715Y1409764D01*
X343984Y1409970D01*
X344099Y1410332D01*
X344022Y1410694D01*
X343830Y1410952D01*
X343562Y1411107D01*
X343294D01*
X343025Y1411004D01*
X342795Y1410745D01*
G01X340347Y1408007D02*
Y1411107D01*
X340807Y1410487D01*
G01Y1408007D02*
X339887D01*
G01X337975Y1410590D02*
X337745Y1410900D01*
X337477Y1411055D01*
X337170Y1411107D01*
X336787Y1411004D01*
X336519Y1410745D01*
X336442Y1410435D01*
X336480Y1410125D01*
X336634Y1409867D01*
X337400Y1409350D01*
X337745Y1408989D01*
X337975Y1408472D01*
X338052Y1408007D01*
X336442D01*
G01X339813Y1443552D02*
X339506Y1443294D01*
X339161Y1443139D01*
X338855D01*
X338548Y1443294D01*
X338318Y1443552D01*
X338203Y1443914D01*
X338280Y1444276D01*
X338471Y1444586D01*
X338816Y1444792D01*
X339276Y1444896D01*
X339545Y1445102D01*
X339660Y1445464D01*
X339583Y1445826D01*
X339391Y1446084D01*
X339123Y1446239D01*
X338855D01*
X338586Y1446136D01*
X338356Y1445877D01*
G01X335908Y1443139D02*
Y1446239D01*
X336368Y1445619D01*
G01Y1443139D02*
X335448D01*
G01X325802Y1442891D02*
Y1445991D01*
X324882D01*
X324575Y1445836D01*
X324345Y1445474D01*
X324268Y1445061D01*
X324345Y1444648D01*
X324537Y1444338D01*
X324882Y1444183D01*
X325802D01*
G01X321935Y1442891D02*
Y1445991D01*
X322395Y1445371D01*
G01Y1442891D02*
X321475D01*
G01X319563Y1444183D02*
X319295Y1444544D01*
X319065Y1444751D01*
X318758Y1444854D01*
X318490Y1444751D01*
X318298Y1444544D01*
X318145Y1444234D01*
X318107Y1443873D01*
X318145Y1443563D01*
X318298Y1443253D01*
X318528Y1442994D01*
X318797Y1442891D01*
X319103Y1442994D01*
X319372Y1443304D01*
X319525Y1443769D01*
X319563Y1444286D01*
X319487Y1444958D01*
X319372Y1445319D01*
X319180Y1445681D01*
X318912Y1445939D01*
X318643Y1445991D01*
X318375Y1445888D01*
X318183Y1445629D01*
G01X325393Y1583062D02*
Y1586162D01*
X324473D01*
X324166Y1586007D01*
X323936Y1585645D01*
X323859Y1585232D01*
X323936Y1584819D01*
X324128Y1584509D01*
X324473Y1584354D01*
X325393D01*
G01X321526Y1583062D02*
Y1586162D01*
X321986Y1585542D01*
G01Y1583062D02*
X321066D01*
G01X318503D02*
X318426Y1583734D01*
X318311Y1584302D01*
X318158Y1584819D01*
X317966Y1585387D01*
X317659Y1586162D01*
X319193D01*
G01X335375Y1585960D02*
X335682Y1586218D01*
X336027Y1586373D01*
X336333D01*
X336640Y1586218D01*
X336870Y1585960D01*
X336985Y1585598D01*
X336908Y1585236D01*
X336717Y1584926D01*
X336372Y1584720D01*
X335912Y1584616D01*
X335643Y1584410D01*
X335528Y1584048D01*
X335605Y1583686D01*
X335797Y1583428D01*
X336065Y1583273D01*
X336333D01*
X336602Y1583376D01*
X336832Y1583635D01*
G01X339280Y1586373D02*
Y1583273D01*
X338820Y1583893D01*
G01Y1586373D02*
X339740D01*
G01X341652Y1583790D02*
X341882Y1583480D01*
X342150Y1583325D01*
X342457Y1583273D01*
X342840Y1583376D01*
X343108Y1583635D01*
X343185Y1583945D01*
X343147Y1584255D01*
X342993Y1584513D01*
X342227Y1585030D01*
X341882Y1585391D01*
X341652Y1585908D01*
X341575Y1586373D01*
X343185D01*
G01X339545Y1618611D02*
X339238Y1618353D01*
X338893Y1618198D01*
X338587D01*
X338280Y1618353D01*
X338050Y1618611D01*
X337935Y1618973D01*
X338012Y1619335D01*
X338203Y1619645D01*
X338548Y1619851D01*
X339008Y1619955D01*
X339277Y1620161D01*
X339392Y1620523D01*
X339315Y1620885D01*
X339123Y1621143D01*
X338855Y1621298D01*
X338587D01*
X338318Y1621195D01*
X338088Y1620936D01*
G01X335640Y1618198D02*
Y1621298D01*
X336100Y1620678D01*
G01Y1618198D02*
X335180D01*
G01X326473Y1618218D02*
Y1621318D01*
X325553D01*
X325246Y1621163D01*
X325016Y1620801D01*
X324939Y1620388D01*
X325016Y1619975D01*
X325208Y1619665D01*
X325553Y1619510D01*
X326473D01*
G01X322606Y1618218D02*
Y1621318D01*
X323066Y1620698D01*
G01Y1618218D02*
X322146D01*
G01X320234Y1619510D02*
X319966Y1619871D01*
X319736Y1620078D01*
X319429Y1620181D01*
X319161Y1620078D01*
X318969Y1619871D01*
X318816Y1619561D01*
X318778Y1619200D01*
X318816Y1618890D01*
X318969Y1618580D01*
X319199Y1618321D01*
X319468Y1618218D01*
X319774Y1618321D01*
X320043Y1618631D01*
X320196Y1619096D01*
X320234Y1619613D01*
X320158Y1620285D01*
X320043Y1620646D01*
X319851Y1621008D01*
X319583Y1621266D01*
X319314Y1621318D01*
X319046Y1621215D01*
X318854Y1620956D01*
G01X326197Y1758236D02*
Y1761336D01*
X325277D01*
X324970Y1761181D01*
X324740Y1760819D01*
X324663Y1760406D01*
X324740Y1759993D01*
X324932Y1759683D01*
X325277Y1759528D01*
X326197D01*
G01X322330Y1758236D02*
Y1761336D01*
X322790Y1760716D01*
G01Y1758236D02*
X321870D01*
G01X319307D02*
X319230Y1758908D01*
X319115Y1759476D01*
X318962Y1759993D01*
X318770Y1760561D01*
X318463Y1761336D01*
X319997D01*
G01X342283Y1758935D02*
X341976Y1758677D01*
X341631Y1758522D01*
X341325D01*
X341018Y1758677D01*
X340788Y1758935D01*
X340673Y1759297D01*
X340750Y1759659D01*
X340941Y1759969D01*
X341286Y1760175D01*
X341746Y1760279D01*
X342015Y1760485D01*
X342130Y1760847D01*
X342053Y1761209D01*
X341861Y1761467D01*
X341593Y1761622D01*
X341325D01*
X341056Y1761519D01*
X340826Y1761260D01*
G01X338378Y1758522D02*
Y1761622D01*
X338838Y1761002D01*
G01Y1758522D02*
X337918D01*
G01X336006Y1761105D02*
X335776Y1761415D01*
X335508Y1761570D01*
X335201Y1761622D01*
X334818Y1761519D01*
X334550Y1761260D01*
X334473Y1760950D01*
X334511Y1760640D01*
X334665Y1760382D01*
X335431Y1759865D01*
X335776Y1759504D01*
X336006Y1758987D01*
X336083Y1758522D01*
X334473D01*
G01X341556Y1793666D02*
X341249Y1793408D01*
X340904Y1793253D01*
X340598D01*
X340291Y1793408D01*
X340061Y1793666D01*
X339946Y1794028D01*
X340023Y1794390D01*
X340214Y1794700D01*
X340559Y1794906D01*
X341019Y1795010D01*
X341288Y1795216D01*
X341403Y1795578D01*
X341326Y1795940D01*
X341134Y1796198D01*
X340866Y1796353D01*
X340598D01*
X340329Y1796250D01*
X340099Y1795991D01*
G01X337651Y1793253D02*
Y1796353D01*
X338111Y1795733D01*
G01Y1793253D02*
X337191D01*
G01X327410Y1793676D02*
Y1796776D01*
X326490D01*
X326183Y1796621D01*
X325953Y1796259D01*
X325876Y1795846D01*
X325953Y1795433D01*
X326145Y1795123D01*
X326490Y1794968D01*
X327410D01*
G01X323543Y1793676D02*
Y1796776D01*
X324003Y1796156D01*
G01Y1793676D02*
X323083D01*
G01X321171Y1794968D02*
X320903Y1795329D01*
X320673Y1795536D01*
X320366Y1795639D01*
X320098Y1795536D01*
X319906Y1795329D01*
X319753Y1795019D01*
X319715Y1794658D01*
X319753Y1794348D01*
X319906Y1794038D01*
X320136Y1793779D01*
X320405Y1793676D01*
X320711Y1793779D01*
X320980Y1794089D01*
X321133Y1794554D01*
X321171Y1795071D01*
X321095Y1795743D01*
X320980Y1796104D01*
X320788Y1796466D01*
X320520Y1796724D01*
X320251Y1796776D01*
X319983Y1796673D01*
X319791Y1796414D01*
G01X326599Y1932507D02*
Y1935607D01*
X325679D01*
X325372Y1935452D01*
X325142Y1935090D01*
X325065Y1934677D01*
X325142Y1934264D01*
X325334Y1933954D01*
X325679Y1933799D01*
X326599D01*
G01X322732Y1932507D02*
Y1935607D01*
X323192Y1934987D01*
G01Y1932507D02*
X322272D01*
G01X319709D02*
X319632Y1933179D01*
X319517Y1933747D01*
X319364Y1934264D01*
X319172Y1934832D01*
X318865Y1935607D01*
X320399D01*
G01X345500Y1933205D02*
X345193Y1932947D01*
X344848Y1932792D01*
X344542D01*
X344235Y1932947D01*
X344005Y1933205D01*
X343890Y1933567D01*
X343967Y1933929D01*
X344158Y1934239D01*
X344503Y1934445D01*
X344963Y1934549D01*
X345232Y1934755D01*
X345347Y1935117D01*
X345270Y1935479D01*
X345078Y1935737D01*
X344810Y1935892D01*
X344542D01*
X344273Y1935789D01*
X344043Y1935530D01*
G01X341595Y1932792D02*
Y1935892D01*
X342055Y1935272D01*
G01Y1932792D02*
X341135D01*
G01X339223Y1935375D02*
X338993Y1935685D01*
X338725Y1935840D01*
X338418Y1935892D01*
X338035Y1935789D01*
X337767Y1935530D01*
X337690Y1935220D01*
X337728Y1934910D01*
X337882Y1934652D01*
X338648Y1934135D01*
X338993Y1933774D01*
X339223Y1933257D01*
X339300Y1932792D01*
X337690D01*
G01X340482Y1968458D02*
X340175Y1968200D01*
X339830Y1968045D01*
X339524D01*
X339217Y1968200D01*
X338987Y1968458D01*
X338872Y1968820D01*
X338949Y1969182D01*
X339140Y1969492D01*
X339485Y1969698D01*
X339945Y1969802D01*
X340214Y1970008D01*
X340329Y1970370D01*
X340252Y1970732D01*
X340060Y1970990D01*
X339792Y1971145D01*
X339524D01*
X339255Y1971042D01*
X339025Y1970783D01*
G01X336577Y1968045D02*
Y1971145D01*
X337037Y1970525D01*
G01Y1968045D02*
X336117D01*
G01X327008Y1968333D02*
Y1971433D01*
X326088D01*
X325781Y1971278D01*
X325551Y1970916D01*
X325474Y1970503D01*
X325551Y1970090D01*
X325743Y1969780D01*
X326088Y1969625D01*
X327008D01*
G01X323141Y1968333D02*
Y1971433D01*
X323601Y1970813D01*
G01Y1968333D02*
X322681D01*
G01X320769Y1969625D02*
X320501Y1969986D01*
X320271Y1970193D01*
X319964Y1970296D01*
X319696Y1970193D01*
X319504Y1969986D01*
X319351Y1969676D01*
X319313Y1969315D01*
X319351Y1969005D01*
X319504Y1968695D01*
X319734Y1968436D01*
X320003Y1968333D01*
X320309Y1968436D01*
X320578Y1968746D01*
X320731Y1969211D01*
X320769Y1969728D01*
X320693Y1970400D01*
X320578Y1970761D01*
X320386Y1971123D01*
X320118Y1971381D01*
X319849Y1971433D01*
X319581Y1971330D01*
X319389Y1971071D01*
G01X350500Y-72000D02*
Y-80000D01*
G01X348200Y-72000D02*
X352800D01*
G01X356600Y-76667D02*
X357300Y-75733D01*
X357900Y-75200D01*
X358700Y-74933D01*
X359400Y-75200D01*
X359900Y-75733D01*
X360300Y-76533D01*
X360400Y-77467D01*
X360300Y-78267D01*
X359900Y-79067D01*
X359300Y-79733D01*
X358600Y-80000D01*
X357800Y-79733D01*
X357100Y-78934D01*
X356700Y-77733D01*
X356600Y-76400D01*
X356800Y-74667D01*
X357100Y-73733D01*
X357600Y-72800D01*
X358300Y-72133D01*
X359000Y-72000D01*
X359700Y-72267D01*
X360200Y-72933D01*
G01X363900Y-80000D02*
Y-72000D01*
X366500Y-78667D01*
X369100Y-72000D01*
Y-80000D01*
G01X371500Y-82667D02*
X377500D01*
G01X380500Y-80000D02*
Y-72000D01*
X382900D01*
X383700Y-72400D01*
X384300Y-73333D01*
X384500Y-74400D01*
X384300Y-75467D01*
X383800Y-76267D01*
X382900Y-76667D01*
X380500D01*
G01X388300Y-80000D02*
Y-72000D01*
X390300D01*
X391100Y-72400D01*
X391700Y-72933D01*
X392200Y-73733D01*
X392600Y-74667D01*
X392700Y-76000D01*
X392600Y-77333D01*
X392200Y-78267D01*
X391700Y-79067D01*
X391100Y-79600D01*
X390300Y-80000D01*
X388300D01*
G01X399300Y-75733D02*
X399700Y-75333D01*
X400000Y-74667D01*
X400200Y-73733D01*
X400000Y-72933D01*
X399600Y-72400D01*
X398900Y-72000D01*
X396200D01*
Y-80000D01*
X399500D01*
X400200Y-79467D01*
X400600Y-78667D01*
X400800Y-77733D01*
X400600Y-76800D01*
X400000Y-76000D01*
X399300Y-75733D01*
X396200D01*
G01X403500Y-82667D02*
X409500D01*
G01X412300Y-80000D02*
Y-72000D01*
X414300D01*
X415100Y-72400D01*
X415700Y-72933D01*
X416200Y-73733D01*
X416600Y-74667D01*
X416700Y-76000D01*
X416600Y-77333D01*
X416200Y-78267D01*
X415700Y-79067D01*
X415100Y-79600D01*
X414300Y-80000D01*
X412300D01*
G01X419500Y-82667D02*
X425500D01*
G01X431300Y-75733D02*
X431700Y-75333D01*
X432000Y-74667D01*
X432200Y-73733D01*
X432000Y-72933D01*
X431600Y-72400D01*
X430900Y-72000D01*
X428200D01*
Y-80000D01*
X431500D01*
X432200Y-79467D01*
X432600Y-78667D01*
X432800Y-77733D01*
X432600Y-76800D01*
X432000Y-76000D01*
X431300Y-75733D01*
X428200D01*
G01X436300Y-80000D02*
Y-72000D01*
X438300D01*
X439100Y-72400D01*
X439700Y-72933D01*
X440200Y-73733D01*
X440600Y-74667D01*
X440700Y-76000D01*
X440600Y-77333D01*
X440200Y-78267D01*
X439700Y-79067D01*
X439100Y-79600D01*
X438300Y-80000D01*
X436300D01*
G01X366223Y8190D02*
X365916Y7932D01*
X365571Y7777D01*
X365265D01*
X364958Y7932D01*
X364728Y8190D01*
X364613Y8552D01*
X364690Y8914D01*
X364881Y9224D01*
X365226Y9430D01*
X365686Y9534D01*
X365955Y9740D01*
X366070Y10102D01*
X365993Y10464D01*
X365801Y10722D01*
X365533Y10877D01*
X365265D01*
X364996Y10774D01*
X364766Y10515D01*
G01X362395Y7777D02*
X362318Y8449D01*
X362203Y9017D01*
X362050Y9534D01*
X361858Y10102D01*
X361551Y10877D01*
X363085D01*
G01X363542Y43075D02*
X363235Y42817D01*
X362890Y42662D01*
X362584D01*
X362277Y42817D01*
X362047Y43075D01*
X361932Y43437D01*
X362009Y43799D01*
X362200Y44109D01*
X362545Y44315D01*
X363005Y44419D01*
X363274Y44625D01*
X363389Y44987D01*
X363312Y45349D01*
X363120Y45607D01*
X362852Y45762D01*
X362584D01*
X362315Y45659D01*
X362085Y45400D01*
G01X360365Y43954D02*
X360097Y44315D01*
X359867Y44522D01*
X359560Y44625D01*
X359292Y44522D01*
X359100Y44315D01*
X358947Y44005D01*
X358909Y43644D01*
X358947Y43334D01*
X359100Y43024D01*
X359330Y42765D01*
X359599Y42662D01*
X359905Y42765D01*
X360174Y43075D01*
X360327Y43540D01*
X360365Y44057D01*
X360289Y44729D01*
X360174Y45090D01*
X359982Y45452D01*
X359714Y45710D01*
X359445Y45762D01*
X359177Y45659D01*
X358985Y45400D01*
G01X378842Y78780D02*
G03I-19000J0D01*
G01X349638Y184191D02*
X349331Y183933D01*
X348986Y183778D01*
X348680D01*
X348373Y183933D01*
X348143Y184191D01*
X348028Y184553D01*
X348105Y184915D01*
X348296Y185225D01*
X348641Y185431D01*
X349101Y185535D01*
X349370Y185741D01*
X349485Y186103D01*
X349408Y186465D01*
X349216Y186723D01*
X348948Y186878D01*
X348680D01*
X348411Y186775D01*
X348181Y186516D01*
G01X345810Y183778D02*
X345733Y184450D01*
X345618Y185018D01*
X345465Y185535D01*
X345273Y186103D01*
X344966Y186878D01*
X346500D01*
G01X364922Y218003D02*
X364615Y217745D01*
X364270Y217590D01*
X363964D01*
X363657Y217745D01*
X363427Y218003D01*
X363312Y218365D01*
X363389Y218727D01*
X363580Y219037D01*
X363925Y219243D01*
X364385Y219347D01*
X364654Y219553D01*
X364769Y219915D01*
X364692Y220277D01*
X364500Y220535D01*
X364232Y220690D01*
X363964D01*
X363695Y220587D01*
X363465Y220328D01*
G01X361745Y218882D02*
X361477Y219243D01*
X361247Y219450D01*
X360940Y219553D01*
X360672Y219450D01*
X360480Y219243D01*
X360327Y218933D01*
X360289Y218572D01*
X360327Y218262D01*
X360480Y217952D01*
X360710Y217693D01*
X360979Y217590D01*
X361285Y217693D01*
X361554Y218003D01*
X361707Y218468D01*
X361745Y218985D01*
X361669Y219657D01*
X361554Y220018D01*
X361362Y220380D01*
X361094Y220638D01*
X360825Y220690D01*
X360557Y220587D01*
X360365Y220328D01*
G01X378842Y253780D02*
G03I-19000J0D01*
G01X364076Y358436D02*
X363769Y358178D01*
X363424Y358023D01*
X363118D01*
X362811Y358178D01*
X362581Y358436D01*
X362466Y358798D01*
X362543Y359160D01*
X362734Y359470D01*
X363079Y359676D01*
X363539Y359780D01*
X363808Y359986D01*
X363923Y360348D01*
X363846Y360710D01*
X363654Y360968D01*
X363386Y361123D01*
X363118D01*
X362849Y361020D01*
X362619Y360761D01*
G01X360248Y358023D02*
X360171Y358695D01*
X360056Y359263D01*
X359903Y359780D01*
X359711Y360348D01*
X359404Y361123D01*
X360938D01*
G01X364345Y393320D02*
X364038Y393062D01*
X363693Y392907D01*
X363387D01*
X363080Y393062D01*
X362850Y393320D01*
X362735Y393682D01*
X362812Y394044D01*
X363003Y394354D01*
X363348Y394560D01*
X363808Y394664D01*
X364077Y394870D01*
X364192Y395232D01*
X364115Y395594D01*
X363923Y395852D01*
X363655Y396007D01*
X363387D01*
X363118Y395904D01*
X362888Y395645D01*
G01X361168Y394199D02*
X360900Y394560D01*
X360670Y394767D01*
X360363Y394870D01*
X360095Y394767D01*
X359903Y394560D01*
X359750Y394250D01*
X359712Y393889D01*
X359750Y393579D01*
X359903Y393269D01*
X360133Y393010D01*
X360402Y392907D01*
X360708Y393010D01*
X360977Y393320D01*
X361130Y393785D01*
X361168Y394302D01*
X361092Y394974D01*
X360977Y395335D01*
X360785Y395697D01*
X360517Y395955D01*
X360248Y396007D01*
X359980Y395904D01*
X359788Y395645D01*
G01X378842Y428779D02*
G03I-19000J0D01*
G01X351296Y439777D02*
G03X364986Y477165I-44212J37389D01*
G01X353620Y534431D02*
X353313Y534173D01*
X352968Y534018D01*
X352662D01*
X352355Y534173D01*
X352125Y534431D01*
X352010Y534793D01*
X352087Y535155D01*
X352278Y535465D01*
X352623Y535671D01*
X353083Y535775D01*
X353352Y535981D01*
X353467Y536343D01*
X353390Y536705D01*
X353198Y536963D01*
X352930Y537118D01*
X352662D01*
X352393Y537015D01*
X352163Y536756D01*
G01X349792Y534018D02*
X349715Y534690D01*
X349600Y535258D01*
X349447Y535775D01*
X349255Y536343D01*
X348948Y537118D01*
X350482D01*
G01X362067Y568243D02*
X361760Y567985D01*
X361415Y567830D01*
X361109D01*
X360802Y567985D01*
X360572Y568243D01*
X360457Y568605D01*
X360534Y568967D01*
X360725Y569277D01*
X361070Y569483D01*
X361530Y569587D01*
X361799Y569793D01*
X361914Y570155D01*
X361837Y570517D01*
X361645Y570775D01*
X361377Y570930D01*
X361109D01*
X360840Y570827D01*
X360610Y570568D01*
G01X358890Y569122D02*
X358622Y569483D01*
X358392Y569690D01*
X358085Y569793D01*
X357817Y569690D01*
X357625Y569483D01*
X357472Y569173D01*
X357434Y568812D01*
X357472Y568502D01*
X357625Y568192D01*
X357855Y567933D01*
X358124Y567830D01*
X358430Y567933D01*
X358699Y568243D01*
X358852Y568708D01*
X358890Y569225D01*
X358814Y569897D01*
X358699Y570258D01*
X358507Y570620D01*
X358239Y570878D01*
X357970Y570930D01*
X357702Y570827D01*
X357510Y570568D01*
G01X378842Y603779D02*
G03I-19000J0D01*
G01X363945Y708280D02*
X363638Y708022D01*
X363293Y707867D01*
X362987D01*
X362680Y708022D01*
X362450Y708280D01*
X362335Y708642D01*
X362412Y709004D01*
X362603Y709314D01*
X362948Y709520D01*
X363408Y709624D01*
X363677Y709830D01*
X363792Y710192D01*
X363715Y710554D01*
X363523Y710812D01*
X363255Y710967D01*
X362987D01*
X362718Y710864D01*
X362488Y710605D01*
G01X360117Y707867D02*
X360040Y708539D01*
X359925Y709107D01*
X359772Y709624D01*
X359580Y710192D01*
X359273Y710967D01*
X360807D01*
G01X363542Y743835D02*
X363235Y743577D01*
X362890Y743422D01*
X362584D01*
X362277Y743577D01*
X362047Y743835D01*
X361932Y744197D01*
X362009Y744559D01*
X362200Y744869D01*
X362545Y745075D01*
X363005Y745179D01*
X363274Y745385D01*
X363389Y745747D01*
X363312Y746109D01*
X363120Y746367D01*
X362852Y746522D01*
X362584D01*
X362315Y746419D01*
X362085Y746160D01*
G01X360365Y744714D02*
X360097Y745075D01*
X359867Y745282D01*
X359560Y745385D01*
X359292Y745282D01*
X359100Y745075D01*
X358947Y744765D01*
X358909Y744404D01*
X358947Y744094D01*
X359100Y743784D01*
X359330Y743525D01*
X359599Y743422D01*
X359905Y743525D01*
X360174Y743835D01*
X360327Y744300D01*
X360365Y744817D01*
X360289Y745489D01*
X360174Y745850D01*
X359982Y746212D01*
X359714Y746470D01*
X359445Y746522D01*
X359177Y746419D01*
X358985Y746160D01*
G01X378842Y778780D02*
G03I-19000J0D01*
G01X352969Y884550D02*
X352662Y884292D01*
X352317Y884137D01*
X352011D01*
X351704Y884292D01*
X351474Y884550D01*
X351359Y884912D01*
X351436Y885274D01*
X351627Y885584D01*
X351972Y885790D01*
X352432Y885894D01*
X352701Y886100D01*
X352816Y886462D01*
X352739Y886824D01*
X352547Y887082D01*
X352279Y887237D01*
X352011D01*
X351742Y887134D01*
X351512Y886875D01*
G01X349141Y884137D02*
X349064Y884809D01*
X348949Y885377D01*
X348796Y885894D01*
X348604Y886462D01*
X348297Y887237D01*
X349831D01*
G01X364385Y918232D02*
X364078Y917974D01*
X363733Y917819D01*
X363427D01*
X363120Y917974D01*
X362890Y918232D01*
X362775Y918594D01*
X362852Y918956D01*
X363043Y919266D01*
X363388Y919472D01*
X363848Y919576D01*
X364117Y919782D01*
X364232Y920144D01*
X364155Y920506D01*
X363963Y920764D01*
X363695Y920919D01*
X363427D01*
X363158Y920816D01*
X362928Y920557D01*
G01X361208Y919111D02*
X360940Y919472D01*
X360710Y919679D01*
X360403Y919782D01*
X360135Y919679D01*
X359943Y919472D01*
X359790Y919162D01*
X359752Y918801D01*
X359790Y918491D01*
X359943Y918181D01*
X360173Y917922D01*
X360442Y917819D01*
X360748Y917922D01*
X361017Y918232D01*
X361170Y918697D01*
X361208Y919214D01*
X361132Y919886D01*
X361017Y920247D01*
X360825Y920609D01*
X360557Y920867D01*
X360288Y920919D01*
X360020Y920816D01*
X359828Y920557D01*
G01X378842Y953780D02*
G03I-19000J0D01*
G01X363005Y1058661D02*
X362698Y1058403D01*
X362353Y1058248D01*
X362047D01*
X361740Y1058403D01*
X361510Y1058661D01*
X361395Y1059023D01*
X361472Y1059385D01*
X361663Y1059695D01*
X362008Y1059901D01*
X362468Y1060005D01*
X362737Y1060211D01*
X362852Y1060573D01*
X362775Y1060935D01*
X362583Y1061193D01*
X362315Y1061348D01*
X362047D01*
X361778Y1061245D01*
X361548Y1060986D01*
G01X359177Y1058248D02*
X359100Y1058920D01*
X358985Y1059488D01*
X358832Y1060005D01*
X358640Y1060573D01*
X358333Y1061348D01*
X359867D01*
G01X363004Y1093410D02*
X362697Y1093152D01*
X362352Y1092997D01*
X362046D01*
X361739Y1093152D01*
X361509Y1093410D01*
X361394Y1093772D01*
X361471Y1094134D01*
X361662Y1094444D01*
X362007Y1094650D01*
X362467Y1094754D01*
X362736Y1094960D01*
X362851Y1095322D01*
X362774Y1095684D01*
X362582Y1095942D01*
X362314Y1096097D01*
X362046D01*
X361777Y1095994D01*
X361547Y1095735D01*
G01X359827Y1094289D02*
X359559Y1094650D01*
X359329Y1094857D01*
X359022Y1094960D01*
X358754Y1094857D01*
X358562Y1094650D01*
X358409Y1094340D01*
X358371Y1093979D01*
X358409Y1093669D01*
X358562Y1093359D01*
X358792Y1093100D01*
X359061Y1092997D01*
X359367Y1093100D01*
X359636Y1093410D01*
X359789Y1093875D01*
X359827Y1094392D01*
X359751Y1095064D01*
X359636Y1095425D01*
X359444Y1095787D01*
X359176Y1096045D01*
X358907Y1096097D01*
X358639Y1095994D01*
X358447Y1095735D01*
G01X378842Y1128779D02*
G03I-19000J0D01*
G01X366263Y1233584D02*
X365956Y1233326D01*
X365611Y1233171D01*
X365305D01*
X364998Y1233326D01*
X364768Y1233584D01*
X364653Y1233946D01*
X364730Y1234308D01*
X364921Y1234618D01*
X365266Y1234824D01*
X365726Y1234928D01*
X365995Y1235134D01*
X366110Y1235496D01*
X366033Y1235858D01*
X365841Y1236116D01*
X365573Y1236271D01*
X365305D01*
X365036Y1236168D01*
X364806Y1235909D01*
G01X362435Y1233171D02*
X362358Y1233843D01*
X362243Y1234411D01*
X362090Y1234928D01*
X361898Y1235496D01*
X361591Y1236271D01*
X363125D01*
G01X361973Y1269407D02*
X361666Y1269149D01*
X361321Y1268994D01*
X361015D01*
X360708Y1269149D01*
X360478Y1269407D01*
X360363Y1269769D01*
X360440Y1270131D01*
X360631Y1270441D01*
X360976Y1270647D01*
X361436Y1270751D01*
X361705Y1270957D01*
X361820Y1271319D01*
X361743Y1271681D01*
X361551Y1271939D01*
X361283Y1272094D01*
X361015D01*
X360746Y1271991D01*
X360516Y1271732D01*
G01X358796Y1270286D02*
X358528Y1270647D01*
X358298Y1270854D01*
X357991Y1270957D01*
X357723Y1270854D01*
X357531Y1270647D01*
X357378Y1270337D01*
X357340Y1269976D01*
X357378Y1269666D01*
X357531Y1269356D01*
X357761Y1269097D01*
X358030Y1268994D01*
X358336Y1269097D01*
X358605Y1269407D01*
X358758Y1269872D01*
X358796Y1270389D01*
X358720Y1271061D01*
X358605Y1271422D01*
X358413Y1271784D01*
X358145Y1272042D01*
X357876Y1272094D01*
X357608Y1271991D01*
X357416Y1271732D01*
G01X378842Y1303780D02*
G03I-19000J0D01*
G01X364613Y1407835D02*
X364306Y1407577D01*
X363961Y1407422D01*
X363655D01*
X363348Y1407577D01*
X363118Y1407835D01*
X363003Y1408197D01*
X363080Y1408559D01*
X363271Y1408869D01*
X363616Y1409075D01*
X364076Y1409179D01*
X364345Y1409385D01*
X364460Y1409747D01*
X364383Y1410109D01*
X364191Y1410367D01*
X363923Y1410522D01*
X363655D01*
X363386Y1410419D01*
X363156Y1410160D01*
G01X360785Y1407422D02*
X360708Y1408094D01*
X360593Y1408662D01*
X360440Y1409179D01*
X360248Y1409747D01*
X359941Y1410522D01*
X361475D01*
G01X362912Y1443405D02*
X362605Y1443147D01*
X362260Y1442992D01*
X361954D01*
X361647Y1443147D01*
X361417Y1443405D01*
X361302Y1443767D01*
X361379Y1444129D01*
X361570Y1444439D01*
X361915Y1444645D01*
X362375Y1444749D01*
X362644Y1444955D01*
X362759Y1445317D01*
X362682Y1445679D01*
X362490Y1445937D01*
X362222Y1446092D01*
X361954D01*
X361685Y1445989D01*
X361455Y1445730D01*
G01X359735Y1444284D02*
X359467Y1444645D01*
X359237Y1444852D01*
X358930Y1444955D01*
X358662Y1444852D01*
X358470Y1444645D01*
X358317Y1444335D01*
X358279Y1443974D01*
X358317Y1443664D01*
X358470Y1443354D01*
X358700Y1443095D01*
X358969Y1442992D01*
X359275Y1443095D01*
X359544Y1443405D01*
X359697Y1443870D01*
X359735Y1444387D01*
X359659Y1445059D01*
X359544Y1445420D01*
X359352Y1445782D01*
X359084Y1446040D01*
X358815Y1446092D01*
X358547Y1445989D01*
X358355Y1445730D01*
G01X378842Y1478780D02*
G03I-19000J0D01*
G01X365192Y1583311D02*
X364885Y1583053D01*
X364540Y1582898D01*
X364234D01*
X363927Y1583053D01*
X363697Y1583311D01*
X363582Y1583673D01*
X363659Y1584035D01*
X363850Y1584345D01*
X364195Y1584551D01*
X364655Y1584655D01*
X364924Y1584861D01*
X365039Y1585223D01*
X364962Y1585585D01*
X364770Y1585843D01*
X364502Y1585998D01*
X364234D01*
X363965Y1585895D01*
X363735Y1585636D01*
G01X361364Y1582898D02*
X361287Y1583570D01*
X361172Y1584138D01*
X361019Y1584655D01*
X360827Y1585223D01*
X360520Y1585998D01*
X362054D01*
G01X363851Y1618463D02*
X363544Y1618205D01*
X363199Y1618050D01*
X362893D01*
X362586Y1618205D01*
X362356Y1618463D01*
X362241Y1618825D01*
X362318Y1619187D01*
X362509Y1619497D01*
X362854Y1619703D01*
X363314Y1619807D01*
X363583Y1620013D01*
X363698Y1620375D01*
X363621Y1620737D01*
X363429Y1620995D01*
X363161Y1621150D01*
X362893D01*
X362624Y1621047D01*
X362394Y1620788D01*
G01X360674Y1619342D02*
X360406Y1619703D01*
X360176Y1619910D01*
X359869Y1620013D01*
X359601Y1619910D01*
X359409Y1619703D01*
X359256Y1619393D01*
X359218Y1619032D01*
X359256Y1618722D01*
X359409Y1618412D01*
X359639Y1618153D01*
X359908Y1618050D01*
X360214Y1618153D01*
X360483Y1618463D01*
X360636Y1618928D01*
X360674Y1619445D01*
X360598Y1620117D01*
X360483Y1620478D01*
X360291Y1620840D01*
X360023Y1621098D01*
X359754Y1621150D01*
X359486Y1621047D01*
X359294Y1620788D01*
G01X378842Y1653780D02*
G03I-19000J0D01*
G01X365325Y1758484D02*
X365018Y1758226D01*
X364673Y1758071D01*
X364367D01*
X364060Y1758226D01*
X363830Y1758484D01*
X363715Y1758846D01*
X363792Y1759208D01*
X363983Y1759518D01*
X364328Y1759724D01*
X364788Y1759828D01*
X365057Y1760034D01*
X365172Y1760396D01*
X365095Y1760758D01*
X364903Y1761016D01*
X364635Y1761171D01*
X364367D01*
X364098Y1761068D01*
X363868Y1760809D01*
G01X361497Y1758071D02*
X361420Y1758743D01*
X361305Y1759311D01*
X361152Y1759828D01*
X360960Y1760396D01*
X360653Y1761171D01*
X362187D01*
G01X366130Y1793117D02*
X365823Y1792859D01*
X365478Y1792704D01*
X365172D01*
X364865Y1792859D01*
X364635Y1793117D01*
X364520Y1793479D01*
X364597Y1793841D01*
X364788Y1794151D01*
X365133Y1794357D01*
X365593Y1794461D01*
X365862Y1794667D01*
X365977Y1795029D01*
X365900Y1795391D01*
X365708Y1795649D01*
X365440Y1795804D01*
X365172D01*
X364903Y1795701D01*
X364673Y1795442D01*
G01X362953Y1793996D02*
X362685Y1794357D01*
X362455Y1794564D01*
X362148Y1794667D01*
X361880Y1794564D01*
X361688Y1794357D01*
X361535Y1794047D01*
X361497Y1793686D01*
X361535Y1793376D01*
X361688Y1793066D01*
X361918Y1792807D01*
X362187Y1792704D01*
X362493Y1792807D01*
X362762Y1793117D01*
X362915Y1793582D01*
X362953Y1794099D01*
X362877Y1794771D01*
X362762Y1795132D01*
X362570Y1795494D01*
X362302Y1795752D01*
X362033Y1795804D01*
X361765Y1795701D01*
X361573Y1795442D01*
G01X378842Y1828779D02*
G03I-19000J0D01*
G01X365861Y1933560D02*
X365554Y1933302D01*
X365209Y1933147D01*
X364903D01*
X364596Y1933302D01*
X364366Y1933560D01*
X364251Y1933922D01*
X364328Y1934284D01*
X364519Y1934594D01*
X364864Y1934800D01*
X365324Y1934904D01*
X365593Y1935110D01*
X365708Y1935472D01*
X365631Y1935834D01*
X365439Y1936092D01*
X365171Y1936247D01*
X364903D01*
X364634Y1936144D01*
X364404Y1935885D01*
G01X362033Y1933147D02*
X361956Y1933819D01*
X361841Y1934387D01*
X361688Y1934904D01*
X361496Y1935472D01*
X361189Y1936247D01*
X362723D01*
G01X363313Y1968846D02*
X363006Y1968588D01*
X362661Y1968433D01*
X362355D01*
X362048Y1968588D01*
X361818Y1968846D01*
X361703Y1969208D01*
X361780Y1969570D01*
X361971Y1969880D01*
X362316Y1970086D01*
X362776Y1970190D01*
X363045Y1970396D01*
X363160Y1970758D01*
X363083Y1971120D01*
X362891Y1971378D01*
X362623Y1971533D01*
X362355D01*
X362086Y1971430D01*
X361856Y1971171D01*
G01X360136Y1969725D02*
X359868Y1970086D01*
X359638Y1970293D01*
X359331Y1970396D01*
X359063Y1970293D01*
X358871Y1970086D01*
X358718Y1969776D01*
X358680Y1969415D01*
X358718Y1969105D01*
X358871Y1968795D01*
X359101Y1968536D01*
X359370Y1968433D01*
X359676Y1968536D01*
X359945Y1968846D01*
X360098Y1969311D01*
X360136Y1969828D01*
X360060Y1970500D01*
X359945Y1970861D01*
X359753Y1971223D01*
X359485Y1971481D01*
X359216Y1971533D01*
X358948Y1971430D01*
X358756Y1971171D01*
G01X378842Y2003780D02*
G03I-19000J0D01*
G01X418149Y1122D02*
Y53288D01*
G01Y176122D02*
Y228288D01*
G01Y351122D02*
Y403288D01*
G01X418150Y526122D02*
Y578288D01*
G01Y701122D02*
Y753288D01*
G01X418149Y876122D02*
Y928288D01*
G01Y1051122D02*
Y1103288D01*
G01Y1226122D02*
Y1278288D01*
G01Y1401122D02*
Y1453288D01*
G01Y1576122D02*
Y1628288D01*
G01Y1751122D02*
Y1803288D01*
G01Y1926122D02*
Y1978288D01*
G01X443300Y-130000D02*
Y-122000D01*
X445300D01*
X446100Y-122400D01*
X446700Y-122933D01*
X447200Y-123733D01*
X447600Y-124667D01*
X447700Y-126000D01*
X447600Y-127333D01*
X447200Y-128267D01*
X446700Y-129067D01*
X446100Y-129600D01*
X445300Y-130000D01*
X443300D01*
G01X473000D02*
Y-122000D01*
X471800Y-123600D01*
G01Y-130000D02*
X474200D01*
G01X478800Y-128800D02*
X479400Y-129467D01*
X480100Y-129867D01*
X481000Y-130000D01*
X481900Y-129733D01*
X482600Y-129200D01*
X483100Y-128267D01*
X483200Y-127200D01*
X483000Y-126133D01*
X482500Y-125467D01*
X481800Y-124933D01*
X481100Y-124800D01*
X480400Y-124933D01*
X479500Y-125467D01*
X479800Y-122000D01*
X482500D01*
M02*
